FILE_TYPE = MACRO_DRAWING;
SET COLOR_WIRE YELLOW;
SET COLOR_PROP MONO;
SET COLOR_DOT WHITE;
SET COLOR_ARC YELLOW;
SET COLOR_BODY GREEN;
SET COLOR_NOTE MONO;
SET PROP_DISPLAY VALUE;
SET PAGE_NUMBER P42;
FORCEADD CAP..1
(-2550 950);
FORCEPROP 1 LAST VOLTAGE 4V
J 0
(-2500 1000);
DISPLAY 0.638298 (-2500 1000);
PAINT SKYBLUE (-2500 1000);
FORCEPROP 1 LAST PART_NUMBER C95333-006
J 0
(-2500 850);
DISPLAY 0.617021 (-2500 850);
PAINT BLUE (-2500 850);
FORCEPROP 0 LAST GROUP PWR_MLCC_CAP
J 0
(-2494 762);
DISPLAY 0.638298 (-2494 762);
PAINT BROWN (-2494 762);
DISPLAY BOTH (-2494 762);
FORCEPROP 1 LASTPIN (-2550 1050) $PN 1
J 0
(-2540 1030);
DISPLAY 0.617021 (-2540 1030);
PAINT ORANGE (-2540 1030);
FORCEPROP 1 LASTPIN (-2550 850) $PN 2
J 0
(-2540 830);
DISPLAY 0.617021 (-2540 830);
PAINT ORANGE (-2540 830);
FORCEPROP 1 LAST PACK_TYPE 0805
J 0
(-2500 800);
DISPLAY 0.617021 (-2500 800);
PAINT SKYBLUE (-2500 800);
FORCEPROP 1 LAST MATERIAL X6S
J 0
(-2500 900);
DISPLAY 0.638298 (-2500 900);
PAINT SKYBLUE (-2500 900);
FORCEPROP 1 LAST TOLERANCE 20%
J 0
(-2500 950);
DISPLAY 0.617021 (-2500 950);
PAINT SKYBLUE (-2500 950);
FORCEPROP 1 LAST VALUE 47UF
J 0
(-2500 1050);
DISPLAY 0.617021 (-2500 1050);
PAINT SKYBLUE (-2500 1050);
FORCEPROP 1 LAST LOCATION C4P1
J 0
(-2500 1100);
DISPLAY 0.617021 (-2500 1100);
PAINT AQUA (-2500 1100);
FORCEPROP 2 LAST BOM_COST PROC_SOCKET
J 0
(-2500 1150);
DISPLAY 1.021277 (-2500 1150);
PAINT ORANGE (-2500 1150);
DISPLAY INVISIBLE (-2500 1150);
FORCEPROP 2 LAST CDS_LIB mstr_discrete
J 0
(-2550 950);
PAINT ORANGE (-2550 950);
DISPLAY INVISIBLE (-2550 950);
FORCEPROP 2 LAST CDS_SEC 1
J 0
(-2490 1170);
PAINT MONO (-2490 1170);
DISPLAY INVISIBLE (-2490 1170);
FORCEPROP 2 LAST $SEC 1
J 0
(-2490 1170);
PAINT MONO (-2490 1170);
DISPLAY INVISIBLE (-2490 1170);
FORCEPROP 2 LAST CDS_LOCATION C4P1
J 0
(-2500 1050);
DISPLAY 0.617021 (-2500 1050);
PAINT AQUA (-2500 1050);
DISPLAY INVISIBLE (-2500 1050);
FORCEPROP 1 LAST PATH I10
J 0
(-2500 1100);
DISPLAY 0.978723 (-2500 1100);
PAINT WHITE (-2500 1100);
DISPLAY INVISIBLE (-2500 1100);
FORCEPROP 2 LAST ROOM PVCCIN_CPU0_DECAP_VR
J 0
(-2500 1100);
DISPLAY 1.021277 (-2500 1100);
PAINT ORANGE (-2500 1100);
DISPLAY INVISIBLE (-2500 1100);
FORCEADD CAP_A..1
(-4900 3800);
FORCEPROP 1 LAST VALUE 22.0UF
J 0
(-4850 3900);
DISPLAY 0.617021 (-4850 3900);
PAINT SKYBLUE (-4850 3900);
FORCEPROP 1 LAST VOLTAGE 4V
J 0
(-4850 3850);
DISPLAY 0.617021 (-4850 3850);
PAINT SKYBLUE (-4850 3850);
FORCEPROP 1 LAST TOLERANCE 20%
J 0
(-4850 3800);
DISPLAY 0.617021 (-4850 3800);
PAINT SKYBLUE (-4850 3800);
FORCEPROP 1 LAST LOCATION C5D28
J 0
(-4850 3950);
DISPLAY 0.617021 (-4850 3950);
PAINT AQUA (-4850 3950);
FORCEPROP 1 LASTPIN (-4900 3900) $PN 1
J 0
(-4890 3880);
DISPLAY 0.617021 (-4890 3880);
PAINT GREEN (-4890 3880);
FORCEPROP 1 LAST MATERIAL X6S
J 0
(-4850 3750);
DISPLAY 0.617021 (-4850 3750);
PAINT SKYBLUE (-4850 3750);
FORCEPROP 1 LAST PART_NUMBER E15431-004
J 0
(-4850 3700);
DISPLAY 0.617021 (-4850 3700);
PAINT BLUE (-4850 3700);
FORCEPROP 1 LAST PACK_TYPE 0603V
J 0
(-4850 3650);
DISPLAY 0.617021 (-4850 3650);
PAINT SKYBLUE (-4850 3650);
FORCEPROP 1 LASTPIN (-4900 3700) $PN 2
J 0
(-4890 3680);
DISPLAY 0.617021 (-4890 3680);
PAINT GREEN (-4890 3680);
FORCEPROP 0 LAST GROUP PWR_MLCC_CAP
J 0
(-4845 3552);
DISPLAY 0.638298 (-4845 3552);
PAINT BROWN (-4845 3552);
DISPLAY BOTH (-4845 3552);
FORCEPROP 2 LAST CDS_LOCATION C5D28
J 0
(-4850 3900);
DISPLAY 0.617021 (-4850 3900);
PAINT AQUA (-4850 3900);
DISPLAY INVISIBLE (-4850 3900);
FORCEPROP 2 LAST BOM_COST PROC_SOCKET
J 0
(-4850 4000);
DISPLAY 1.021277 (-4850 4000);
PAINT ORANGE (-4850 4000);
DISPLAY INVISIBLE (-4850 4000);
FORCEPROP 2 LAST CDS_LIB dev_discrete
J 0
(-4900 3800);
PAINT ORANGE (-4900 3800);
DISPLAY INVISIBLE (-4900 3800);
FORCEPROP 2 LAST CDS_SEC 1
J 0
(-4850 4000);
PAINT MONO (-4850 4000);
DISPLAY INVISIBLE (-4850 4000);
FORCEPROP 2 LAST $SEC 1
J 0
(-4850 4000);
PAINT MONO (-4850 4000);
DISPLAY INVISIBLE (-4850 4000);
FORCEPROP 1 LAST PATH I100
J 0
(-4850 3950);
DISPLAY 0.978723 (-4850 3950);
PAINT WHITE (-4850 3950);
DISPLAY INVISIBLE (-4850 3950);
FORCEPROP 2 LAST ROOM PVCCIN_CPU0_DECAP_VR
J 0
(-4850 3950);
DISPLAY 1.021277 (-4850 3950);
PAINT ORANGE (-4850 3950);
DISPLAY INVISIBLE (-4850 3950);
FORCEADD GND..1
(-5950 3525);
FORCEPROP 3 LASTPIN (-5950 3575) SIG_NAME GND\g
J 0
(-5940 3585);
DISPLAY 0.659574 (-5940 3585);
PAINT MONO (-5940 3585);
DISPLAY INVISIBLE (-5940 3585);
FORCEPROP 1 LAST HDL_POWER GND
J 0
(-5950 3675);
DISPLAY 0.893617 (-5950 3675);
PAINT GREEN (-5950 3675);
DISPLAY INVISIBLE (-5950 3675);
FORCEPROP 1 LAST PATH I101
J 0
(-5875 3525);
DISPLAY 0.872340 (-5875 3525);
PAINT AQUA (-5875 3525);
DISPLAY INVISIBLE (-5875 3525);
FORCEPROP 1 LAST BODY_TYPE PLUMBING
J 0
(-5995 3482);
DISPLAY 0.340426 (-5995 3482);
PAINT GREEN (-5995 3482);
DISPLAY INVISIBLE (-5995 3482);
FORCEPROP 1 LAST SIZE 1B
J 0
(-5875 3475);
DISPLAY 0.893617 (-5875 3475);
PAINT GREEN (-5875 3475);
DISPLAY INVISIBLE (-5875 3475);
FORCEPROP 2 LAST CDS_LIB mstr_symbols
J 0
(-5950 3525);
PAINT ORANGE (-5950 3525);
DISPLAY INVISIBLE (-5950 3525);
FORCEPROP 1 LAST VOLTAGE 0
J 0
(-5950 3525);
PAINT SKYBLUE (-5950 3525);
DISPLAY INVISIBLE (-5950 3525);
FORCEADD CAP_A..1
(-4750 4500);
FORCEPROP 0 LAST GROUP PWR_MLCC_CAP
J 0
(-4695 4302);
DISPLAY 0.638298 (-4695 4302);
PAINT BROWN (-4695 4302);
DISPLAY BOTH (-4695 4302);
FORCEPROP 1 LAST VALUE 22.0UF
J 0
(-4700 4600);
DISPLAY 0.617021 (-4700 4600);
PAINT SKYBLUE (-4700 4600);
FORCEPROP 1 LAST PACK_TYPE 0603V
J 0
(-4700 4350);
DISPLAY 0.617021 (-4700 4350);
PAINT SKYBLUE (-4700 4350);
FORCEPROP 1 LAST TOLERANCE 20%
J 0
(-4700 4500);
DISPLAY 0.617021 (-4700 4500);
PAINT SKYBLUE (-4700 4500);
FORCEPROP 1 LAST VOLTAGE 4V
J 0
(-4700 4550);
DISPLAY 0.617021 (-4700 4550);
PAINT SKYBLUE (-4700 4550);
FORCEPROP 1 LASTPIN (-4750 4600) $PN 1
J 0
(-4740 4580);
DISPLAY 0.617021 (-4740 4580);
PAINT GREEN (-4740 4580);
FORCEPROP 1 LAST LOCATION C5D29
J 0
(-4700 4650);
DISPLAY 0.617021 (-4700 4650);
PAINT AQUA (-4700 4650);
FORCEPROP 1 LASTPIN (-4750 4400) $PN 2
J 0
(-4740 4380);
DISPLAY 0.617021 (-4740 4380);
PAINT GREEN (-4740 4380);
FORCEPROP 1 LAST MATERIAL X6S
J 0
(-4700 4450);
DISPLAY 0.617021 (-4700 4450);
PAINT SKYBLUE (-4700 4450);
FORCEPROP 1 LAST PART_NUMBER E15431-004
J 0
(-4700 4400);
DISPLAY 0.617021 (-4700 4400);
PAINT BLUE (-4700 4400);
FORCEPROP 2 LAST CDS_LOCATION C5D29
J 0
(-4700 4600);
DISPLAY 0.617021 (-4700 4600);
PAINT AQUA (-4700 4600);
DISPLAY INVISIBLE (-4700 4600);
FORCEPROP 2 LAST BOM_COST PROC_SOCKET
J 0
(-4700 4700);
DISPLAY 1.021277 (-4700 4700);
PAINT ORANGE (-4700 4700);
DISPLAY INVISIBLE (-4700 4700);
FORCEPROP 2 LAST CDS_LIB dev_discrete
J 0
(-4750 4500);
PAINT ORANGE (-4750 4500);
DISPLAY INVISIBLE (-4750 4500);
FORCEPROP 2 LAST CDS_SEC 1
J 0
(-4700 4700);
PAINT MONO (-4700 4700);
DISPLAY INVISIBLE (-4700 4700);
FORCEPROP 2 LAST $SEC 1
J 0
(-4700 4700);
PAINT MONO (-4700 4700);
DISPLAY INVISIBLE (-4700 4700);
FORCEPROP 1 LAST PATH I102
J 0
(-4700 4650);
DISPLAY 0.978723 (-4700 4650);
PAINT WHITE (-4700 4650);
DISPLAY INVISIBLE (-4700 4650);
FORCEPROP 2 LAST ROOM PVCCIN_CPU0_DECAP_VR
J 0
(-4700 4650);
DISPLAY 1.021277 (-4700 4650);
PAINT ORANGE (-4700 4650);
DISPLAY INVISIBLE (-4700 4650);
FORCEADD CAP_A..1
(-5050 4500);
FORCEPROP 1 LAST VALUE 22.0UF
J 0
(-5000 4600);
DISPLAY 0.617021 (-5000 4600);
PAINT SKYBLUE (-5000 4600);
FORCEPROP 0 LAST GROUP PWR_MLCC_CAP
J 0
(-4995 4252);
DISPLAY 0.638298 (-4995 4252);
PAINT BROWN (-4995 4252);
DISPLAY BOTH (-4995 4252);
FORCEPROP 1 LASTPIN (-5050 4600) $PN 1
J 0
(-5040 4580);
DISPLAY 0.617021 (-5040 4580);
PAINT GREEN (-5040 4580);
FORCEPROP 1 LAST LOCATION C5D32
J 0
(-5000 4650);
DISPLAY 0.617021 (-5000 4650);
PAINT AQUA (-5000 4650);
FORCEPROP 1 LAST VOLTAGE 4V
J 0
(-5000 4550);
DISPLAY 0.617021 (-5000 4550);
PAINT SKYBLUE (-5000 4550);
FORCEPROP 1 LAST TOLERANCE 20%
J 0
(-5000 4500);
DISPLAY 0.617021 (-5000 4500);
PAINT SKYBLUE (-5000 4500);
FORCEPROP 1 LAST PACK_TYPE 0603V
J 0
(-5000 4350);
DISPLAY 0.617021 (-5000 4350);
PAINT SKYBLUE (-5000 4350);
FORCEPROP 1 LASTPIN (-5050 4400) $PN 2
J 0
(-5040 4380);
DISPLAY 0.617021 (-5040 4380);
PAINT GREEN (-5040 4380);
FORCEPROP 1 LAST MATERIAL X6S
J 0
(-5000 4450);
DISPLAY 0.617021 (-5000 4450);
PAINT SKYBLUE (-5000 4450);
FORCEPROP 1 LAST PART_NUMBER E15431-004
J 0
(-5000 4400);
DISPLAY 0.617021 (-5000 4400);
PAINT BLUE (-5000 4400);
FORCEPROP 2 LAST ROOM PVCCIN_CPU0_DECAP_VR
J 0
(-5000 4650);
DISPLAY 1.021277 (-5000 4650);
PAINT ORANGE (-5000 4650);
DISPLAY INVISIBLE (-5000 4650);
FORCEPROP 1 LAST PATH I103
J 0
(-5000 4650);
DISPLAY 0.978723 (-5000 4650);
PAINT WHITE (-5000 4650);
DISPLAY INVISIBLE (-5000 4650);
FORCEPROP 2 LAST $SEC 1
J 0
(-5000 4700);
PAINT MONO (-5000 4700);
DISPLAY INVISIBLE (-5000 4700);
FORCEPROP 2 LAST CDS_SEC 1
J 0
(-5000 4700);
PAINT MONO (-5000 4700);
DISPLAY INVISIBLE (-5000 4700);
FORCEPROP 2 LAST CDS_LIB dev_discrete
J 0
(-5050 4500);
PAINT ORANGE (-5050 4500);
DISPLAY INVISIBLE (-5050 4500);
FORCEPROP 2 LAST BOM_COST PROC_SOCKET
J 0
(-5000 4700);
DISPLAY 1.021277 (-5000 4700);
PAINT ORANGE (-5000 4700);
DISPLAY INVISIBLE (-5000 4700);
FORCEPROP 2 LAST CDS_LOCATION C5D32
J 0
(-5000 4600);
DISPLAY 0.617021 (-5000 4600);
PAINT AQUA (-5000 4600);
DISPLAY INVISIBLE (-5000 4600);
FORCEADD CAP_A..1
(-5350 4500);
FORCEPROP 1 LAST VALUE 22.0UF
J 0
(-5300 4600);
DISPLAY 0.617021 (-5300 4600);
PAINT SKYBLUE (-5300 4600);
FORCEPROP 0 LAST GROUP PWR_MLCC_CAP
J 0
(-5295 4302);
DISPLAY 0.638298 (-5295 4302);
PAINT BROWN (-5295 4302);
DISPLAY BOTH (-5295 4302);
FORCEPROP 1 LASTPIN (-5350 4400) $PN 2
J 0
(-5340 4380);
DISPLAY 0.617021 (-5340 4380);
PAINT GREEN (-5340 4380);
FORCEPROP 1 LASTPIN (-5350 4600) $PN 1
J 0
(-5340 4580);
DISPLAY 0.617021 (-5340 4580);
PAINT GREEN (-5340 4580);
FORCEPROP 1 LAST MATERIAL X6S
J 0
(-5300 4450);
DISPLAY 0.617021 (-5300 4450);
PAINT SKYBLUE (-5300 4450);
FORCEPROP 1 LAST VOLTAGE 4V
J 0
(-5300 4550);
DISPLAY 0.617021 (-5300 4550);
PAINT SKYBLUE (-5300 4550);
FORCEPROP 1 LAST TOLERANCE 20%
J 0
(-5300 4500);
DISPLAY 0.617021 (-5300 4500);
PAINT SKYBLUE (-5300 4500);
FORCEPROP 1 LAST PACK_TYPE 0603V
J 0
(-5300 4350);
DISPLAY 0.617021 (-5300 4350);
PAINT SKYBLUE (-5300 4350);
FORCEPROP 1 LAST PART_NUMBER E15431-004
J 0
(-5300 4400);
DISPLAY 0.617021 (-5300 4400);
PAINT BLUE (-5300 4400);
FORCEPROP 1 LAST LOCATION C5D47
J 0
(-5300 4650);
DISPLAY 0.617021 (-5300 4650);
PAINT AQUA (-5300 4650);
FORCEPROP 2 LAST ROOM PVCCIN_CPU0_DECAP_VR
J 0
(-5300 4650);
DISPLAY 1.021277 (-5300 4650);
PAINT ORANGE (-5300 4650);
DISPLAY INVISIBLE (-5300 4650);
FORCEPROP 1 LAST PATH I104
J 0
(-5300 4650);
DISPLAY 0.978723 (-5300 4650);
PAINT WHITE (-5300 4650);
DISPLAY INVISIBLE (-5300 4650);
FORCEPROP 2 LAST $SEC 1
J 0
(-5300 4700);
PAINT MONO (-5300 4700);
DISPLAY INVISIBLE (-5300 4700);
FORCEPROP 2 LAST CDS_SEC 1
J 0
(-5300 4700);
PAINT MONO (-5300 4700);
DISPLAY INVISIBLE (-5300 4700);
FORCEPROP 2 LAST CDS_LIB dev_discrete
J 0
(-5350 4500);
PAINT ORANGE (-5350 4500);
DISPLAY INVISIBLE (-5350 4500);
FORCEPROP 2 LAST BOM_COST PROC_SOCKET
J 0
(-5300 4700);
DISPLAY 1.021277 (-5300 4700);
PAINT ORANGE (-5300 4700);
DISPLAY INVISIBLE (-5300 4700);
FORCEPROP 2 LAST CDS_LOCATION C5D47
J 0
(-5300 4600);
DISPLAY 0.617021 (-5300 4600);
PAINT AQUA (-5300 4600);
DISPLAY INVISIBLE (-5300 4600);
FORCEADD GND..1
(-5950 4225);
FORCEPROP 3 LASTPIN (-5950 4275) SIG_NAME GND\g
J 0
(-5940 4285);
DISPLAY 0.659574 (-5940 4285);
PAINT MONO (-5940 4285);
DISPLAY INVISIBLE (-5940 4285);
FORCEPROP 1 LAST VOLTAGE 0
J 0
(-5950 4225);
PAINT SKYBLUE (-5950 4225);
DISPLAY INVISIBLE (-5950 4225);
FORCEPROP 1 LAST SIZE 1B
J 0
(-5875 4175);
DISPLAY 0.893617 (-5875 4175);
PAINT GREEN (-5875 4175);
DISPLAY INVISIBLE (-5875 4175);
FORCEPROP 2 LAST CDS_LIB mstr_symbols
J 0
(-5950 4225);
PAINT ORANGE (-5950 4225);
DISPLAY INVISIBLE (-5950 4225);
FORCEPROP 1 LAST BODY_TYPE PLUMBING
J 0
(-5995 4182);
DISPLAY 0.340426 (-5995 4182);
PAINT GREEN (-5995 4182);
DISPLAY INVISIBLE (-5995 4182);
FORCEPROP 1 LAST PATH I105
J 0
(-5875 4225);
DISPLAY 0.872340 (-5875 4225);
PAINT AQUA (-5875 4225);
DISPLAY INVISIBLE (-5875 4225);
FORCEPROP 1 LAST HDL_POWER GND
J 0
(-5950 4375);
DISPLAY 0.893617 (-5950 4375);
PAINT GREEN (-5950 4375);
DISPLAY INVISIBLE (-5950 4375);
FORCEADD CAP_A..1
(-5200 3800);
FORCEPROP 1 LAST TOLERANCE 20%
J 0
(-5150 3800);
DISPLAY 0.617021 (-5150 3800);
PAINT SKYBLUE (-5150 3800);
FORCEPROP 1 LASTPIN (-5200 3700) $PN 2
J 0
(-5190 3680);
DISPLAY 0.617021 (-5190 3680);
PAINT GREEN (-5190 3680);
FORCEPROP 1 LASTPIN (-5200 3900) $PN 1
J 0
(-5190 3880);
DISPLAY 0.617021 (-5190 3880);
PAINT GREEN (-5190 3880);
FORCEPROP 1 LAST MATERIAL X6S
J 0
(-5150 3750);
DISPLAY 0.617021 (-5150 3750);
PAINT SKYBLUE (-5150 3750);
FORCEPROP 1 LAST LOCATION C5D31
J 0
(-5150 3950);
DISPLAY 0.617021 (-5150 3950);
PAINT AQUA (-5150 3950);
FORCEPROP 1 LAST VALUE 22.0UF
J 0
(-5150 3900);
DISPLAY 0.617021 (-5150 3900);
PAINT SKYBLUE (-5150 3900);
FORCEPROP 1 LAST VOLTAGE 4V
J 0
(-5150 3850);
DISPLAY 0.617021 (-5150 3850);
PAINT SKYBLUE (-5150 3850);
FORCEPROP 0 LAST GROUP PWR_MLCC_CAP
J 0
(-5145 3602);
DISPLAY 0.638298 (-5145 3602);
PAINT BROWN (-5145 3602);
DISPLAY BOTH (-5145 3602);
FORCEPROP 1 LAST PACK_TYPE 0603V
J 0
(-5150 3650);
DISPLAY 0.617021 (-5150 3650);
PAINT SKYBLUE (-5150 3650);
FORCEPROP 1 LAST PART_NUMBER E15431-004
J 0
(-5150 3700);
DISPLAY 0.617021 (-5150 3700);
PAINT BLUE (-5150 3700);
FORCEPROP 2 LAST CDS_LOCATION C5D31
J 0
(-5150 3900);
DISPLAY 0.617021 (-5150 3900);
PAINT AQUA (-5150 3900);
DISPLAY INVISIBLE (-5150 3900);
FORCEPROP 2 LAST BOM_COST PROC_SOCKET
J 0
(-5150 4000);
DISPLAY 1.021277 (-5150 4000);
PAINT ORANGE (-5150 4000);
DISPLAY INVISIBLE (-5150 4000);
FORCEPROP 2 LAST CDS_LIB dev_discrete
J 0
(-5200 3800);
PAINT ORANGE (-5200 3800);
DISPLAY INVISIBLE (-5200 3800);
FORCEPROP 2 LAST CDS_SEC 1
J 0
(-5150 4000);
PAINT MONO (-5150 4000);
DISPLAY INVISIBLE (-5150 4000);
FORCEPROP 2 LAST $SEC 1
J 0
(-5150 4000);
PAINT MONO (-5150 4000);
DISPLAY INVISIBLE (-5150 4000);
FORCEPROP 1 LAST PATH I106
J 0
(-5150 3950);
DISPLAY 0.978723 (-5150 3950);
PAINT WHITE (-5150 3950);
DISPLAY INVISIBLE (-5150 3950);
FORCEPROP 2 LAST ROOM PVCCIN_CPU0_DECAP_VR
J 0
(-5150 3950);
DISPLAY 1.021277 (-5150 3950);
PAINT ORANGE (-5150 3950);
DISPLAY INVISIBLE (-5150 3950);
FORCEADD CAP_A..1
(-5500 3800);
FORCEPROP 1 LAST LOCATION C5D46
J 0
(-5450 3950);
DISPLAY 0.617021 (-5450 3950);
PAINT AQUA (-5450 3950);
FORCEPROP 1 LAST VALUE 22.0UF
J 0
(-5450 3900);
DISPLAY 0.617021 (-5450 3900);
PAINT SKYBLUE (-5450 3900);
FORCEPROP 1 LASTPIN (-5500 3900) $PN 1
J 0
(-5490 3880);
DISPLAY 0.617021 (-5490 3880);
PAINT GREEN (-5490 3880);
FORCEPROP 1 LAST VOLTAGE 4V
J 0
(-5450 3850);
DISPLAY 0.617021 (-5450 3850);
PAINT SKYBLUE (-5450 3850);
FORCEPROP 1 LAST TOLERANCE 20%
J 0
(-5450 3800);
DISPLAY 0.617021 (-5450 3800);
PAINT SKYBLUE (-5450 3800);
FORCEPROP 1 LAST MATERIAL X6S
J 0
(-5450 3750);
DISPLAY 0.617021 (-5450 3750);
PAINT SKYBLUE (-5450 3750);
FORCEPROP 1 LASTPIN (-5500 3700) $PN 2
J 0
(-5490 3680);
DISPLAY 0.617021 (-5490 3680);
PAINT GREEN (-5490 3680);
FORCEPROP 1 LAST PART_NUMBER E15431-004
J 0
(-5450 3700);
DISPLAY 0.617021 (-5450 3700);
PAINT BLUE (-5450 3700);
FORCEPROP 1 LAST PACK_TYPE 0603V
J 0
(-5450 3650);
DISPLAY 0.617021 (-5450 3650);
PAINT SKYBLUE (-5450 3650);
FORCEPROP 0 LAST GROUP PWR_MLCC_CAP
J 0
(-5445 3552);
DISPLAY 0.638298 (-5445 3552);
PAINT BROWN (-5445 3552);
DISPLAY BOTH (-5445 3552);
FORCEPROP 2 LAST ROOM PVCCIN_CPU0_DECAP_VR
J 0
(-5450 3950);
DISPLAY 1.021277 (-5450 3950);
PAINT ORANGE (-5450 3950);
DISPLAY INVISIBLE (-5450 3950);
FORCEPROP 1 LAST PATH I107
J 0
(-5450 3950);
DISPLAY 0.978723 (-5450 3950);
PAINT WHITE (-5450 3950);
DISPLAY INVISIBLE (-5450 3950);
FORCEPROP 2 LAST $SEC 1
J 0
(-5450 4000);
PAINT MONO (-5450 4000);
DISPLAY INVISIBLE (-5450 4000);
FORCEPROP 2 LAST CDS_SEC 1
J 0
(-5450 4000);
PAINT MONO (-5450 4000);
DISPLAY INVISIBLE (-5450 4000);
FORCEPROP 2 LAST CDS_LIB dev_discrete
J 0
(-5500 3800);
PAINT ORANGE (-5500 3800);
DISPLAY INVISIBLE (-5500 3800);
FORCEPROP 2 LAST BOM_COST PROC_SOCKET
J 0
(-5450 4000);
DISPLAY 1.021277 (-5450 4000);
PAINT ORANGE (-5450 4000);
DISPLAY INVISIBLE (-5450 4000);
FORCEPROP 2 LAST CDS_LOCATION C5D46
J 0
(-5450 3900);
DISPLAY 0.617021 (-5450 3900);
PAINT AQUA (-5450 3900);
DISPLAY INVISIBLE (-5450 3900);
FORCEADD CAP..1
(-4100 3150);
FORCEPROP 1 LAST PART_NUMBER E15431-001
J 0
(-4050 3000);
DISPLAY 0.617021 (-4050 3000);
PAINT BLUE (-4050 3000);
FORCEPROP 1 LAST MATERIAL X6S
J 0
(-4050 3050);
DISPLAY 0.617021 (-4050 3050);
PAINT SKYBLUE (-4050 3050);
FORCEPROP 1 LAST PACK_TYPE 0603LF
J 0
(-4050 2950);
DISPLAY 0.617021 (-4050 2950);
PAINT SKYBLUE (-4050 2950);
FORCEPROP 0 LAST GROUP PWR_MLCC_CAP
J 0
(-4045 2902);
DISPLAY 0.638298 (-4045 2902);
PAINT BROWN (-4045 2902);
DISPLAY BOTH (-4045 2902);
FORCEPROP 1 LAST TOLERANCE 20%
J 0
(-4050 3100);
DISPLAY 0.617021 (-4050 3100);
PAINT SKYBLUE (-4050 3100);
FORCEPROP 1 LASTPIN (-4100 3050) $PN 2
J 0
(-4090 3030);
DISPLAY 0.617021 (-4090 3030);
PAINT GREEN (-4090 3030);
FORCEPROP 1 LAST VALUE 10UF
J 0
(-4050 3200);
DISPLAY 0.617021 (-4050 3200);
PAINT SKYBLUE (-4050 3200);
FORCEPROP 1 LASTPIN (-4100 3250) $PN 1
J 0
(-4090 3230);
DISPLAY 0.617021 (-4090 3230);
PAINT GREEN (-4090 3230);
FORCEPROP 1 LAST VOLTAGE 4V
J 0
(-4050 3150);
DISPLAY 0.617021 (-4050 3150);
PAINT SKYBLUE (-4050 3150);
FORCEPROP 1 LAST LOCATION C5D10
J 0
(-4050 3250);
DISPLAY 0.617021 (-4050 3250);
PAINT AQUA (-4050 3250);
FORCEPROP 2 LAST ROOM PVCCIN_CPU0_DECAP_VR
J 0
(-4050 3300);
DISPLAY 1.021277 (-4050 3300);
PAINT ORANGE (-4050 3300);
DISPLAY INVISIBLE (-4050 3300);
FORCEPROP 1 LAST PATH I108
J 0
(-4050 3300);
DISPLAY 0.978723 (-4050 3300);
PAINT WHITE (-4050 3300);
DISPLAY INVISIBLE (-4050 3300);
FORCEPROP 2 LAST CDS_LOCATION C5D10
J 0
(-4050 3250);
DISPLAY 0.617021 (-4050 3250);
PAINT AQUA (-4050 3250);
DISPLAY INVISIBLE (-4050 3250);
FORCEPROP 2 LAST $SEC 1
J 0
(-4050 3350);
PAINT MONO (-4050 3350);
DISPLAY INVISIBLE (-4050 3350);
FORCEPROP 2 LAST CDS_SEC 1
J 0
(-4050 3350);
PAINT MONO (-4050 3350);
DISPLAY INVISIBLE (-4050 3350);
FORCEPROP 2 LAST CDS_LIB mstr_discrete
J 0
(-4100 3150);
PAINT ORANGE (-4100 3150);
DISPLAY INVISIBLE (-4100 3150);
FORCEPROP 2 LAST BOM_COST PROC_SOCKET
J 0
(-4050 3350);
DISPLAY 1.021277 (-4050 3350);
PAINT ORANGE (-4050 3350);
DISPLAY INVISIBLE (-4050 3350);
FORCEADD CAP_A..1
(-5000 3150);
FORCEPROP 1 LAST LOCATION C5D27
J 0
(-4950 3300);
DISPLAY 0.617021 (-4950 3300);
PAINT AQUA (-4950 3300);
FORCEPROP 1 LAST MATERIAL X6S
J 0
(-4950 3100);
DISPLAY 0.617021 (-4950 3100);
PAINT SKYBLUE (-4950 3100);
FORCEPROP 1 LASTPIN (-5000 3050) $PN 2
J 0
(-4990 3030);
DISPLAY 0.617021 (-4990 3030);
PAINT GREEN (-4990 3030);
FORCEPROP 1 LAST PART_NUMBER E15431-004
J 0
(-4950 3050);
DISPLAY 0.617021 (-4950 3050);
PAINT BLUE (-4950 3050);
FORCEPROP 1 LASTPIN (-5000 3250) $PN 1
J 0
(-4990 3230);
DISPLAY 0.617021 (-4990 3230);
PAINT GREEN (-4990 3230);
FORCEPROP 1 LAST VALUE 22.0UF
J 0
(-4950 3250);
DISPLAY 0.617021 (-4950 3250);
PAINT SKYBLUE (-4950 3250);
FORCEPROP 1 LAST VOLTAGE 4V
J 0
(-4950 3200);
DISPLAY 0.617021 (-4950 3200);
PAINT SKYBLUE (-4950 3200);
FORCEPROP 1 LAST TOLERANCE 20%
J 0
(-4950 3150);
DISPLAY 0.617021 (-4950 3150);
PAINT SKYBLUE (-4950 3150);
FORCEPROP 1 LAST PACK_TYPE 0603V
J 0
(-4950 3000);
DISPLAY 0.617021 (-4950 3000);
PAINT SKYBLUE (-4950 3000);
FORCEPROP 0 LAST GROUP PWR_MLCC_CAP
J 0
(-4945 2902);
DISPLAY 0.638298 (-4945 2902);
PAINT BROWN (-4945 2902);
DISPLAY BOTH (-4945 2902);
FORCEPROP 2 LAST ROOM PVCCIN_CPU0_DECAP_VR
J 0
(-4950 3300);
DISPLAY 1.021277 (-4950 3300);
PAINT ORANGE (-4950 3300);
DISPLAY INVISIBLE (-4950 3300);
FORCEPROP 1 LAST PATH I109
J 0
(-4950 3300);
DISPLAY 0.978723 (-4950 3300);
PAINT WHITE (-4950 3300);
DISPLAY INVISIBLE (-4950 3300);
FORCEPROP 2 LAST $SEC 1
J 0
(-4950 3350);
PAINT MONO (-4950 3350);
DISPLAY INVISIBLE (-4950 3350);
FORCEPROP 2 LAST CDS_SEC 1
J 0
(-4950 3350);
PAINT MONO (-4950 3350);
DISPLAY INVISIBLE (-4950 3350);
FORCEPROP 2 LAST CDS_LIB dev_discrete
J 0
(-5000 3150);
PAINT ORANGE (-5000 3150);
DISPLAY INVISIBLE (-5000 3150);
FORCEPROP 2 LAST BOM_COST PROC_SOCKET
J 0
(-4950 3350);
DISPLAY 1.021277 (-4950 3350);
PAINT ORANGE (-4950 3350);
DISPLAY INVISIBLE (-4950 3350);
FORCEPROP 2 LAST CDS_LOCATION C5D27
J 0
(-4950 3250);
DISPLAY 0.617021 (-4950 3250);
PAINT AQUA (-4950 3250);
DISPLAY INVISIBLE (-4950 3250);
FORCEADD GND..1
(-5950 2875);
FORCEPROP 3 LASTPIN (-5950 2925) SIG_NAME GND\g
J 0
(-5940 2935);
DISPLAY 0.659574 (-5940 2935);
PAINT MONO (-5940 2935);
DISPLAY INVISIBLE (-5940 2935);
FORCEPROP 1 LAST VOLTAGE 0
J 0
(-5950 2875);
PAINT SKYBLUE (-5950 2875);
DISPLAY INVISIBLE (-5950 2875);
FORCEPROP 1 LAST SIZE 1B
J 0
(-5875 2825);
DISPLAY 0.893617 (-5875 2825);
PAINT GREEN (-5875 2825);
DISPLAY INVISIBLE (-5875 2825);
FORCEPROP 2 LAST CDS_LIB mstr_symbols
J 0
(-5950 2875);
PAINT ORANGE (-5950 2875);
DISPLAY INVISIBLE (-5950 2875);
FORCEPROP 1 LAST BODY_TYPE PLUMBING
J 0
(-5995 2832);
DISPLAY 0.340426 (-5995 2832);
PAINT GREEN (-5995 2832);
DISPLAY INVISIBLE (-5995 2832);
FORCEPROP 1 LAST PATH I110
J 0
(-5875 2875);
DISPLAY 0.872340 (-5875 2875);
PAINT AQUA (-5875 2875);
DISPLAY INVISIBLE (-5875 2875);
FORCEPROP 1 LAST HDL_POWER GND
J 0
(-5950 3025);
DISPLAY 0.893617 (-5950 3025);
PAINT GREEN (-5950 3025);
DISPLAY INVISIBLE (-5950 3025);
FORCEADD CAP_A..1
(-5300 3150);
FORCEPROP 1 LAST PACK_TYPE 0603V
J 0
(-5250 3000);
DISPLAY 0.617021 (-5250 3000);
PAINT SKYBLUE (-5250 3000);
FORCEPROP 1 LAST MATERIAL X6S
J 0
(-5250 3100);
DISPLAY 0.617021 (-5250 3100);
PAINT SKYBLUE (-5250 3100);
FORCEPROP 1 LASTPIN (-5300 3050) $PN 2
J 0
(-5290 3030);
DISPLAY 0.617021 (-5290 3030);
PAINT GREEN (-5290 3030);
FORCEPROP 1 LASTPIN (-5300 3250) $PN 1
J 0
(-5290 3230);
DISPLAY 0.617021 (-5290 3230);
PAINT GREEN (-5290 3230);
FORCEPROP 1 LAST TOLERANCE 20%
J 0
(-5250 3150);
DISPLAY 0.617021 (-5250 3150);
PAINT SKYBLUE (-5250 3150);
FORCEPROP 1 LAST VOLTAGE 4V
J 0
(-5250 3200);
DISPLAY 0.617021 (-5250 3200);
PAINT SKYBLUE (-5250 3200);
FORCEPROP 1 LAST VALUE 22.0UF
J 0
(-5250 3250);
DISPLAY 0.617021 (-5250 3250);
PAINT SKYBLUE (-5250 3250);
FORCEPROP 1 LAST PART_NUMBER E15431-004
J 0
(-5250 3050);
DISPLAY 0.617021 (-5250 3050);
PAINT BLUE (-5250 3050);
FORCEPROP 0 LAST GROUP PWR_MLCC_CAP
J 0
(-5245 2952);
DISPLAY 0.638298 (-5245 2952);
PAINT BROWN (-5245 2952);
DISPLAY BOTH (-5245 2952);
FORCEPROP 1 LAST LOCATION C5D30
J 0
(-5250 3300);
DISPLAY 0.617021 (-5250 3300);
PAINT AQUA (-5250 3300);
FORCEPROP 2 LAST CDS_LOCATION C5D30
J 0
(-5250 3250);
DISPLAY 0.617021 (-5250 3250);
PAINT AQUA (-5250 3250);
DISPLAY INVISIBLE (-5250 3250);
FORCEPROP 2 LAST BOM_COST PROC_SOCKET
J 0
(-5250 3350);
DISPLAY 1.021277 (-5250 3350);
PAINT ORANGE (-5250 3350);
DISPLAY INVISIBLE (-5250 3350);
FORCEPROP 2 LAST CDS_LIB dev_discrete
J 0
(-5300 3150);
PAINT ORANGE (-5300 3150);
DISPLAY INVISIBLE (-5300 3150);
FORCEPROP 2 LAST CDS_SEC 1
J 0
(-5250 3350);
PAINT MONO (-5250 3350);
DISPLAY INVISIBLE (-5250 3350);
FORCEPROP 2 LAST $SEC 1
J 0
(-5250 3350);
PAINT MONO (-5250 3350);
DISPLAY INVISIBLE (-5250 3350);
FORCEPROP 1 LAST PATH I111
J 0
(-5250 3300);
DISPLAY 0.978723 (-5250 3300);
PAINT WHITE (-5250 3300);
DISPLAY INVISIBLE (-5250 3300);
FORCEPROP 2 LAST ROOM PVCCIN_CPU0_DECAP_VR
J 0
(-5250 3300);
DISPLAY 1.021277 (-5250 3300);
PAINT ORANGE (-5250 3300);
DISPLAY INVISIBLE (-5250 3300);
FORCEADD CAP_A..1
(-5800 3800);
FORCEPROP 1 LAST LOCATION C5D41
J 0
(-5750 3950);
DISPLAY 0.617021 (-5750 3950);
PAINT AQUA (-5750 3950);
FORCEPROP 1 LAST VALUE 22.0UF
J 0
(-5750 3900);
DISPLAY 0.617021 (-5750 3900);
PAINT SKYBLUE (-5750 3900);
FORCEPROP 1 LAST VOLTAGE 4V
J 0
(-5750 3850);
DISPLAY 0.617021 (-5750 3850);
PAINT SKYBLUE (-5750 3850);
FORCEPROP 1 LAST TOLERANCE 20%
J 0
(-5750 3800);
DISPLAY 0.617021 (-5750 3800);
PAINT SKYBLUE (-5750 3800);
FORCEPROP 1 LAST PACK_TYPE 0603V
J 0
(-5750 3650);
DISPLAY 0.617021 (-5750 3650);
PAINT SKYBLUE (-5750 3650);
FORCEPROP 1 LASTPIN (-5800 3700) $PN 2
J 0
(-5790 3680);
DISPLAY 0.617021 (-5790 3680);
PAINT GREEN (-5790 3680);
FORCEPROP 1 LASTPIN (-5800 3900) $PN 1
J 0
(-5790 3880);
DISPLAY 0.617021 (-5790 3880);
PAINT GREEN (-5790 3880);
FORCEPROP 1 LAST MATERIAL X6S
J 0
(-5750 3750);
DISPLAY 0.617021 (-5750 3750);
PAINT SKYBLUE (-5750 3750);
FORCEPROP 1 LAST PART_NUMBER E15431-004
J 0
(-5750 3700);
DISPLAY 0.617021 (-5750 3700);
PAINT BLUE (-5750 3700);
FORCEPROP 0 LAST GROUP PWR_MLCC_CAP
J 0
(-5745 3602);
DISPLAY 0.638298 (-5745 3602);
PAINT BROWN (-5745 3602);
DISPLAY BOTH (-5745 3602);
FORCEPROP 2 LAST CDS_LOCATION C5D41
J 0
(-5750 3900);
DISPLAY 0.617021 (-5750 3900);
PAINT AQUA (-5750 3900);
DISPLAY INVISIBLE (-5750 3900);
FORCEPROP 2 LAST BOM_COST PROC_SOCKET
J 0
(-5750 4000);
DISPLAY 1.021277 (-5750 4000);
PAINT ORANGE (-5750 4000);
DISPLAY INVISIBLE (-5750 4000);
FORCEPROP 2 LAST CDS_LIB dev_discrete
J 0
(-5800 3800);
PAINT ORANGE (-5800 3800);
DISPLAY INVISIBLE (-5800 3800);
FORCEPROP 2 LAST CDS_SEC 1
J 0
(-5750 4000);
PAINT MONO (-5750 4000);
DISPLAY INVISIBLE (-5750 4000);
FORCEPROP 2 LAST $SEC 1
J 0
(-5750 4000);
PAINT MONO (-5750 4000);
DISPLAY INVISIBLE (-5750 4000);
FORCEPROP 1 LAST PATH I114
J 0
(-5750 3950);
DISPLAY 0.978723 (-5750 3950);
PAINT WHITE (-5750 3950);
DISPLAY INVISIBLE (-5750 3950);
FORCEPROP 2 LAST ROOM PVCCIN_CPU0_DECAP_VR
J 0
(-5750 3950);
DISPLAY 1.021277 (-5750 3950);
PAINT ORANGE (-5750 3950);
DISPLAY INVISIBLE (-5750 3950);
FORCEADD CAP_A..1
(-5650 4500);
FORCEPROP 1 LAST MATERIAL X6S
J 0
(-5600 4450);
DISPLAY 0.617021 (-5600 4450);
PAINT SKYBLUE (-5600 4450);
FORCEPROP 1 LAST PART_NUMBER E15431-004
J 0
(-5600 4400);
DISPLAY 0.617021 (-5600 4400);
PAINT BLUE (-5600 4400);
FORCEPROP 1 LAST PACK_TYPE 0603V
J 0
(-5600 4350);
DISPLAY 0.617021 (-5600 4350);
PAINT SKYBLUE (-5600 4350);
FORCEPROP 1 LASTPIN (-5650 4600) $PN 1
J 0
(-5640 4580);
DISPLAY 0.617021 (-5640 4580);
PAINT GREEN (-5640 4580);
FORCEPROP 1 LASTPIN (-5650 4400) $PN 2
J 0
(-5640 4380);
DISPLAY 0.617021 (-5640 4380);
PAINT GREEN (-5640 4380);
FORCEPROP 1 LAST VOLTAGE 4V
J 0
(-5600 4550);
DISPLAY 0.617021 (-5600 4550);
PAINT SKYBLUE (-5600 4550);
FORCEPROP 1 LAST TOLERANCE 20%
J 0
(-5600 4500);
DISPLAY 0.617021 (-5600 4500);
PAINT SKYBLUE (-5600 4500);
FORCEPROP 1 LAST VALUE 22.0UF
J 0
(-5600 4600);
DISPLAY 0.617021 (-5600 4600);
PAINT SKYBLUE (-5600 4600);
FORCEPROP 1 LAST LOCATION C5D40
J 0
(-5600 4650);
DISPLAY 0.617021 (-5600 4650);
PAINT AQUA (-5600 4650);
FORCEPROP 0 LAST GROUP PWR_MLCC_CAP
J 0
(-5595 4252);
DISPLAY 0.638298 (-5595 4252);
PAINT BROWN (-5595 4252);
DISPLAY BOTH (-5595 4252);
FORCEPROP 2 LAST ROOM PVCCIN_CPU0_DECAP_VR
J 0
(-5600 4650);
DISPLAY 1.021277 (-5600 4650);
PAINT ORANGE (-5600 4650);
DISPLAY INVISIBLE (-5600 4650);
FORCEPROP 1 LAST PATH I115
J 0
(-5600 4650);
DISPLAY 0.978723 (-5600 4650);
PAINT WHITE (-5600 4650);
DISPLAY INVISIBLE (-5600 4650);
FORCEPROP 2 LAST $SEC 1
J 0
(-5600 4700);
PAINT MONO (-5600 4700);
DISPLAY INVISIBLE (-5600 4700);
FORCEPROP 2 LAST CDS_SEC 1
J 0
(-5600 4700);
PAINT MONO (-5600 4700);
DISPLAY INVISIBLE (-5600 4700);
FORCEPROP 2 LAST CDS_LIB dev_discrete
J 0
(-5650 4500);
PAINT ORANGE (-5650 4500);
DISPLAY INVISIBLE (-5650 4500);
FORCEPROP 2 LAST BOM_COST PROC_SOCKET
J 0
(-5600 4700);
DISPLAY 1.021277 (-5600 4700);
PAINT ORANGE (-5600 4700);
DISPLAY INVISIBLE (-5600 4700);
FORCEPROP 2 LAST CDS_LOCATION C5D40
J 0
(-5600 4600);
DISPLAY 0.617021 (-5600 4600);
PAINT AQUA (-5600 4600);
DISPLAY INVISIBLE (-5600 4600);
FORCEADD PVCCIN_CPU0..1
(-5950 4800);
FORCEPROP 3 LASTPIN (-5950 4750) SIG_NAME PVCCIN_CPU0\g
J 0
(-5940 4760);
DISPLAY 0.659574 (-5940 4760);
PAINT MONO (-5940 4760);
DISPLAY INVISIBLE (-5940 4760);
FORCEPROP 1 LAST HDL_POWER PVCCIN_CPU0
J 1
(-5950 4850);
DISPLAY 0.872340 (-5950 4850);
PAINT GREEN (-5950 4850);
DISPLAY INVISIBLE (-5950 4850);
FORCEPROP 1 LAST PATH I116
J 0
(-5900 4825);
DISPLAY 0.872340 (-5900 4825);
PAINT AQUA (-5900 4825);
DISPLAY INVISIBLE (-5900 4825);
FORCEPROP 1 LAST BODY_TYPE PLUMBING
J 0
(-5995 4757);
DISPLAY 0.340426 (-5995 4757);
PAINT GREEN (-5995 4757);
DISPLAY INVISIBLE (-5995 4757);
FORCEPROP 2 LAST CDS_LIB mstr_symbols
J 0
(-5950 4800);
PAINT ORANGE (-5950 4800);
DISPLAY INVISIBLE (-5950 4800);
FORCEPROP 1 LAST VOLTAGE 2.0V
J 0
(-5995 4757);
DISPLAY 0.340426 (-5995 4757);
PAINT SKYBLUE (-5995 4757);
DISPLAY INVISIBLE (-5995 4757);
FORCEADD CAP_A..1
(-5950 4500);
FORCEPROP 1 LASTPIN (-5950 4400) $PN 2
J 0
(-5940 4380);
DISPLAY 0.617021 (-5940 4380);
PAINT GREEN (-5940 4380);
FORCEPROP 1 LAST LOCATION C5D14
J 0
(-5900 4650);
DISPLAY 0.617021 (-5900 4650);
PAINT AQUA (-5900 4650);
FORCEPROP 1 LASTPIN (-5950 4600) $PN 1
J 0
(-5940 4580);
DISPLAY 0.617021 (-5940 4580);
PAINT GREEN (-5940 4580);
FORCEPROP 1 LAST VALUE 22.0UF
J 0
(-5900 4600);
DISPLAY 0.617021 (-5900 4600);
PAINT SKYBLUE (-5900 4600);
FORCEPROP 1 LAST VOLTAGE 4V
J 0
(-5900 4550);
DISPLAY 0.617021 (-5900 4550);
PAINT SKYBLUE (-5900 4550);
FORCEPROP 1 LAST TOLERANCE 20%
J 0
(-5900 4500);
DISPLAY 0.617021 (-5900 4500);
PAINT SKYBLUE (-5900 4500);
FORCEPROP 1 LAST MATERIAL X6S
J 0
(-5900 4450);
DISPLAY 0.617021 (-5900 4450);
PAINT SKYBLUE (-5900 4450);
FORCEPROP 1 LAST PART_NUMBER E15431-004
J 0
(-5900 4400);
DISPLAY 0.617021 (-5900 4400);
PAINT BLUE (-5900 4400);
FORCEPROP 1 LAST PACK_TYPE 0603V
J 0
(-5900 4350);
DISPLAY 0.617021 (-5900 4350);
PAINT SKYBLUE (-5900 4350);
FORCEPROP 0 LAST GROUP PWR_MLCC_CAP
J 0
(-5895 4302);
DISPLAY 0.638298 (-5895 4302);
PAINT BROWN (-5895 4302);
DISPLAY BOTH (-5895 4302);
FORCEPROP 2 LAST ROOM PVCCIN_CPU0_DECAP_VR
J 0
(-5900 4650);
DISPLAY 1.021277 (-5900 4650);
PAINT ORANGE (-5900 4650);
DISPLAY INVISIBLE (-5900 4650);
FORCEPROP 1 LAST PATH I117
J 0
(-5900 4650);
DISPLAY 0.978723 (-5900 4650);
PAINT WHITE (-5900 4650);
DISPLAY INVISIBLE (-5900 4650);
FORCEPROP 2 LAST $SEC 1
J 0
(-5900 4700);
PAINT MONO (-5900 4700);
DISPLAY INVISIBLE (-5900 4700);
FORCEPROP 2 LAST CDS_SEC 1
J 0
(-5900 4700);
PAINT MONO (-5900 4700);
DISPLAY INVISIBLE (-5900 4700);
FORCEPROP 2 LAST CDS_LIB dev_discrete
J 0
(-5950 4500);
PAINT ORANGE (-5950 4500);
DISPLAY INVISIBLE (-5950 4500);
FORCEPROP 2 LAST BOM_COST PROC_SOCKET
J 0
(-5900 4700);
DISPLAY 1.021277 (-5900 4700);
PAINT ORANGE (-5900 4700);
DISPLAY INVISIBLE (-5900 4700);
FORCEPROP 2 LAST CDS_LOCATION C5D14
J 0
(-5900 4600);
DISPLAY 0.617021 (-5900 4600);
PAINT AQUA (-5900 4600);
DISPLAY INVISIBLE (-5900 4600);
FORCEADD CAP_A..1
(-6750 4500);
FORCEPROP 1 LAST TOLERANCE 20%
J 0
(-6700 4500);
DISPLAY 0.617021 (-6700 4500);
PAINT SKYBLUE (-6700 4500);
FORCEPROP 1 LAST MATERIAL X6S
J 0
(-6700 4450);
DISPLAY 0.617021 (-6700 4450);
PAINT SKYBLUE (-6700 4450);
FORCEPROP 1 LASTPIN (-6750 4400) $PN 2
J 0
(-6740 4380);
DISPLAY 0.617021 (-6740 4380);
PAINT GREEN (-6740 4380);
FORCEPROP 1 LASTPIN (-6750 4600) $PN 1
J 0
(-6740 4580);
DISPLAY 0.617021 (-6740 4580);
PAINT GREEN (-6740 4580);
FORCEPROP 1 LAST VOLTAGE 4V
J 0
(-6700 4550);
DISPLAY 0.617021 (-6700 4550);
PAINT SKYBLUE (-6700 4550);
FORCEPROP 1 LAST LOCATION C5D17
J 0
(-6700 4650);
DISPLAY 0.617021 (-6700 4650);
PAINT AQUA (-6700 4650);
FORCEPROP 1 LAST VALUE 22.0UF
J 0
(-6700 4600);
DISPLAY 0.617021 (-6700 4600);
PAINT SKYBLUE (-6700 4600);
FORCEPROP 1 LAST PART_NUMBER E15431-004
J 0
(-6700 4400);
DISPLAY 0.617021 (-6700 4400);
PAINT BLUE (-6700 4400);
FORCEPROP 1 LAST PACK_TYPE 0603V
J 0
(-6700 4350);
DISPLAY 0.617021 (-6700 4350);
PAINT SKYBLUE (-6700 4350);
FORCEPROP 0 LAST GROUP PWR_MLCC_CAP
J 0
(-6695 4252);
DISPLAY 0.638298 (-6695 4252);
PAINT BROWN (-6695 4252);
DISPLAY BOTH (-6695 4252);
FORCEPROP 2 LAST ROOM PVCCIN_CPU0_DECAP_VR
J 0
(-6700 4650);
DISPLAY 1.021277 (-6700 4650);
PAINT ORANGE (-6700 4650);
DISPLAY INVISIBLE (-6700 4650);
FORCEPROP 1 LAST PATH I118
J 0
(-6700 4650);
DISPLAY 0.978723 (-6700 4650);
PAINT WHITE (-6700 4650);
DISPLAY INVISIBLE (-6700 4650);
FORCEPROP 2 LAST $SEC 1
J 0
(-6700 4700);
PAINT MONO (-6700 4700);
DISPLAY INVISIBLE (-6700 4700);
FORCEPROP 2 LAST CDS_SEC 1
J 0
(-6700 4700);
PAINT MONO (-6700 4700);
DISPLAY INVISIBLE (-6700 4700);
FORCEPROP 2 LAST CDS_LIB dev_discrete
J 0
(-6750 4500);
PAINT ORANGE (-6750 4500);
DISPLAY INVISIBLE (-6750 4500);
FORCEPROP 2 LAST BOM_COST PROC_SOCKET
J 0
(-6700 4700);
DISPLAY 1.021277 (-6700 4700);
PAINT ORANGE (-6700 4700);
DISPLAY INVISIBLE (-6700 4700);
FORCEPROP 2 LAST CDS_LOCATION C5D17
J 0
(-6700 4600);
DISPLAY 0.617021 (-6700 4600);
PAINT AQUA (-6700 4600);
DISPLAY INVISIBLE (-6700 4600);
FORCEADD PVCCIN_CPU0..1
(-5950 4100);
FORCEPROP 3 LASTPIN (-5950 4050) SIG_NAME PVCCIN_CPU0\g
J 0
(-5940 4060);
DISPLAY 0.659574 (-5940 4060);
PAINT MONO (-5940 4060);
DISPLAY INVISIBLE (-5940 4060);
FORCEPROP 1 LAST HDL_POWER PVCCIN_CPU0
J 1
(-5950 4150);
DISPLAY 0.872340 (-5950 4150);
PAINT GREEN (-5950 4150);
DISPLAY INVISIBLE (-5950 4150);
FORCEPROP 1 LAST PATH I119
J 0
(-5900 4125);
DISPLAY 0.872340 (-5900 4125);
PAINT AQUA (-5900 4125);
DISPLAY INVISIBLE (-5900 4125);
FORCEPROP 1 LAST BODY_TYPE PLUMBING
J 0
(-5995 4057);
DISPLAY 0.340426 (-5995 4057);
PAINT GREEN (-5995 4057);
DISPLAY INVISIBLE (-5995 4057);
FORCEPROP 2 LAST CDS_LIB mstr_symbols
J 0
(-5950 4100);
PAINT ORANGE (-5950 4100);
DISPLAY INVISIBLE (-5950 4100);
FORCEPROP 1 LAST VOLTAGE 2.0V
J 0
(-5995 4057);
DISPLAY 0.340426 (-5995 4057);
PAINT SKYBLUE (-5995 4057);
DISPLAY INVISIBLE (-5995 4057);
FORCEADD CAP..1
(-2850 950);
FORCEPROP 1 LASTPIN (-2850 1050) $PN 1
J 0
(-2840 1030);
DISPLAY 0.617021 (-2840 1030);
PAINT ORANGE (-2840 1030);
FORCEPROP 1 LAST VOLTAGE 4V
J 0
(-2800 1000);
DISPLAY 0.638298 (-2800 1000);
PAINT SKYBLUE (-2800 1000);
FORCEPROP 1 LAST VALUE 47UF
J 0
(-2800 1050);
DISPLAY 0.617021 (-2800 1050);
PAINT SKYBLUE (-2800 1050);
FORCEPROP 1 LAST LOCATION C4P9
J 0
(-2800 1100);
DISPLAY 0.617021 (-2800 1100);
PAINT AQUA (-2800 1100);
FORCEPROP 1 LAST PACK_TYPE 0805
J 0
(-2800 800);
DISPLAY 0.617021 (-2800 800);
PAINT SKYBLUE (-2800 800);
FORCEPROP 0 LAST GROUP PWR_MLCC_CAP
J 0
(-2794 712);
DISPLAY 0.638298 (-2794 712);
PAINT BROWN (-2794 712);
DISPLAY BOTH (-2794 712);
FORCEPROP 1 LASTPIN (-2850 850) $PN 2
J 0
(-2840 830);
DISPLAY 0.617021 (-2840 830);
PAINT ORANGE (-2840 830);
FORCEPROP 1 LAST PART_NUMBER C95333-006
J 0
(-2800 850);
DISPLAY 0.617021 (-2800 850);
PAINT BLUE (-2800 850);
FORCEPROP 1 LAST MATERIAL X6S
J 0
(-2800 900);
DISPLAY 0.638298 (-2800 900);
PAINT SKYBLUE (-2800 900);
FORCEPROP 1 LAST TOLERANCE 20%
J 0
(-2800 950);
DISPLAY 0.617021 (-2800 950);
PAINT SKYBLUE (-2800 950);
FORCEPROP 2 LAST BOM_COST PROC_SOCKET
J 0
(-2800 1150);
DISPLAY 1.021277 (-2800 1150);
PAINT ORANGE (-2800 1150);
DISPLAY INVISIBLE (-2800 1150);
FORCEPROP 2 LAST CDS_LIB mstr_discrete
J 0
(-2850 950);
PAINT ORANGE (-2850 950);
DISPLAY INVISIBLE (-2850 950);
FORCEPROP 2 LAST CDS_SEC 1
J 0
(-2790 1170);
PAINT MONO (-2790 1170);
DISPLAY INVISIBLE (-2790 1170);
FORCEPROP 2 LAST $SEC 1
J 0
(-2790 1170);
PAINT MONO (-2790 1170);
DISPLAY INVISIBLE (-2790 1170);
FORCEPROP 2 LAST CDS_LOCATION C4P9
J 0
(-2800 1050);
DISPLAY 0.617021 (-2800 1050);
PAINT AQUA (-2800 1050);
DISPLAY INVISIBLE (-2800 1050);
FORCEPROP 1 LAST PATH I12
J 0
(-2800 1100);
DISPLAY 0.978723 (-2800 1100);
PAINT WHITE (-2800 1100);
DISPLAY INVISIBLE (-2800 1100);
FORCEPROP 2 LAST ROOM PVCCIN_CPU0_DECAP_VR
J 0
(-2800 1100);
DISPLAY 1.021277 (-2800 1100);
PAINT ORANGE (-2800 1100);
DISPLAY INVISIBLE (-2800 1100);
FORCEADD PVCCIN_CPU0..1
(-5950 3425);
FORCEPROP 3 LASTPIN (-5950 3375) SIG_NAME PVCCIN_CPU0\g
J 0
(-5940 3385);
DISPLAY 0.659574 (-5940 3385);
PAINT MONO (-5940 3385);
DISPLAY INVISIBLE (-5940 3385);
FORCEPROP 1 LAST HDL_POWER PVCCIN_CPU0
J 1
(-5950 3475);
DISPLAY 0.872340 (-5950 3475);
PAINT GREEN (-5950 3475);
DISPLAY INVISIBLE (-5950 3475);
FORCEPROP 1 LAST PATH I121
J 0
(-5900 3450);
DISPLAY 0.872340 (-5900 3450);
PAINT AQUA (-5900 3450);
DISPLAY INVISIBLE (-5900 3450);
FORCEPROP 1 LAST BODY_TYPE PLUMBING
J 0
(-5995 3382);
DISPLAY 0.340426 (-5995 3382);
PAINT GREEN (-5995 3382);
DISPLAY INVISIBLE (-5995 3382);
FORCEPROP 2 LAST CDS_LIB mstr_symbols
J 0
(-5950 3425);
PAINT ORANGE (-5950 3425);
DISPLAY INVISIBLE (-5950 3425);
FORCEPROP 1 LAST VOLTAGE 2.0V
J 0
(-5995 3382);
DISPLAY 0.340426 (-5995 3382);
PAINT SKYBLUE (-5995 3382);
DISPLAY INVISIBLE (-5995 3382);
FORCEADD GND..1
(-7750 4225);
FORCEPROP 3 LASTPIN (-7750 4275) SIG_NAME GND\g
J 0
(-7740 4285);
DISPLAY 0.659574 (-7740 4285);
PAINT MONO (-7740 4285);
DISPLAY INVISIBLE (-7740 4285);
FORCEPROP 1 LAST VOLTAGE 0
J 0
(-7750 4225);
PAINT SKYBLUE (-7750 4225);
DISPLAY INVISIBLE (-7750 4225);
FORCEPROP 1 LAST SIZE 1B
J 0
(-7675 4175);
DISPLAY 0.893617 (-7675 4175);
PAINT GREEN (-7675 4175);
DISPLAY INVISIBLE (-7675 4175);
FORCEPROP 2 LAST CDS_LIB mstr_symbols
J 0
(-7750 4225);
PAINT ORANGE (-7750 4225);
DISPLAY INVISIBLE (-7750 4225);
FORCEPROP 1 LAST BODY_TYPE PLUMBING
J 0
(-7795 4182);
DISPLAY 0.340426 (-7795 4182);
PAINT GREEN (-7795 4182);
DISPLAY INVISIBLE (-7795 4182);
FORCEPROP 1 LAST PATH I122
J 0
(-7675 4225);
DISPLAY 0.872340 (-7675 4225);
PAINT AQUA (-7675 4225);
DISPLAY INVISIBLE (-7675 4225);
FORCEPROP 1 LAST HDL_POWER GND
J 0
(-7750 4375);
DISPLAY 0.893617 (-7750 4375);
PAINT GREEN (-7750 4375);
DISPLAY INVISIBLE (-7750 4375);
FORCEADD CAP_A..1
(-6750 3800);
FORCEPROP 0 LAST GROUP PWR_MLCC_CAP
J 0
(-6695 3552);
DISPLAY 0.638298 (-6695 3552);
PAINT BROWN (-6695 3552);
DISPLAY BOTH (-6695 3552);
FORCEPROP 1 LAST LOCATION C5D16
J 0
(-6700 3950);
DISPLAY 0.617021 (-6700 3950);
PAINT AQUA (-6700 3950);
FORCEPROP 1 LAST VOLTAGE 4V
J 0
(-6700 3850);
DISPLAY 0.617021 (-6700 3850);
PAINT SKYBLUE (-6700 3850);
FORCEPROP 1 LAST TOLERANCE 20%
J 0
(-6700 3800);
DISPLAY 0.617021 (-6700 3800);
PAINT SKYBLUE (-6700 3800);
FORCEPROP 1 LAST MATERIAL X6S
J 0
(-6700 3750);
DISPLAY 0.617021 (-6700 3750);
PAINT SKYBLUE (-6700 3750);
FORCEPROP 1 LAST PACK_TYPE 0603V
J 0
(-6700 3650);
DISPLAY 0.617021 (-6700 3650);
PAINT SKYBLUE (-6700 3650);
FORCEPROP 1 LAST PART_NUMBER E15431-004
J 0
(-6700 3700);
DISPLAY 0.617021 (-6700 3700);
PAINT BLUE (-6700 3700);
FORCEPROP 1 LASTPIN (-6750 3700) $PN 2
J 0
(-6740 3680);
DISPLAY 0.617021 (-6740 3680);
PAINT GREEN (-6740 3680);
FORCEPROP 1 LAST VALUE 22.0UF
J 0
(-6700 3900);
DISPLAY 0.617021 (-6700 3900);
PAINT SKYBLUE (-6700 3900);
FORCEPROP 1 LASTPIN (-6750 3900) $PN 1
J 0
(-6740 3880);
DISPLAY 0.617021 (-6740 3880);
PAINT GREEN (-6740 3880);
FORCEPROP 2 LAST CDS_LOCATION C5D16
J 0
(-6700 3900);
DISPLAY 0.617021 (-6700 3900);
PAINT AQUA (-6700 3900);
DISPLAY INVISIBLE (-6700 3900);
FORCEPROP 2 LAST BOM_COST PROC_SOCKET
J 0
(-6700 4000);
DISPLAY 1.021277 (-6700 4000);
PAINT ORANGE (-6700 4000);
DISPLAY INVISIBLE (-6700 4000);
FORCEPROP 2 LAST CDS_LIB dev_discrete
J 0
(-6750 3800);
PAINT ORANGE (-6750 3800);
DISPLAY INVISIBLE (-6750 3800);
FORCEPROP 2 LAST CDS_SEC 1
J 0
(-6700 4000);
PAINT MONO (-6700 4000);
DISPLAY INVISIBLE (-6700 4000);
FORCEPROP 2 LAST $SEC 1
J 0
(-6700 4000);
PAINT MONO (-6700 4000);
DISPLAY INVISIBLE (-6700 4000);
FORCEPROP 1 LAST PATH I123
J 0
(-6700 3950);
DISPLAY 0.978723 (-6700 3950);
PAINT WHITE (-6700 3950);
DISPLAY INVISIBLE (-6700 3950);
FORCEPROP 2 LAST ROOM PVCCIN_CPU0_DECAP_VR
J 0
(-6700 3950);
DISPLAY 1.021277 (-6700 3950);
PAINT ORANGE (-6700 3950);
DISPLAY INVISIBLE (-6700 3950);
FORCEADD GND..1
(-7750 3525);
FORCEPROP 3 LASTPIN (-7750 3575) SIG_NAME GND\g
J 0
(-7740 3585);
DISPLAY 0.659574 (-7740 3585);
PAINT MONO (-7740 3585);
DISPLAY INVISIBLE (-7740 3585);
FORCEPROP 1 LAST VOLTAGE 0
J 0
(-7750 3525);
PAINT SKYBLUE (-7750 3525);
DISPLAY INVISIBLE (-7750 3525);
FORCEPROP 1 LAST SIZE 1B
J 0
(-7675 3475);
DISPLAY 0.893617 (-7675 3475);
PAINT GREEN (-7675 3475);
DISPLAY INVISIBLE (-7675 3475);
FORCEPROP 2 LAST CDS_LIB mstr_symbols
J 0
(-7750 3525);
PAINT ORANGE (-7750 3525);
DISPLAY INVISIBLE (-7750 3525);
FORCEPROP 1 LAST BODY_TYPE PLUMBING
J 0
(-7795 3482);
DISPLAY 0.340426 (-7795 3482);
PAINT GREEN (-7795 3482);
DISPLAY INVISIBLE (-7795 3482);
FORCEPROP 1 LAST PATH I124
J 0
(-7675 3525);
DISPLAY 0.872340 (-7675 3525);
PAINT AQUA (-7675 3525);
DISPLAY INVISIBLE (-7675 3525);
FORCEPROP 1 LAST HDL_POWER GND
J 0
(-7750 3675);
DISPLAY 0.893617 (-7750 3675);
PAINT GREEN (-7750 3675);
DISPLAY INVISIBLE (-7750 3675);
FORCEADD CAP_A..1
(-7050 4500);
FORCEPROP 1 LAST PACK_TYPE 0603V
J 0
(-7000 4350);
DISPLAY 0.617021 (-7000 4350);
PAINT SKYBLUE (-7000 4350);
FORCEPROP 1 LAST MATERIAL X6S
J 0
(-7000 4450);
DISPLAY 0.617021 (-7000 4450);
PAINT SKYBLUE (-7000 4450);
FORCEPROP 1 LAST PART_NUMBER E15431-004
J 0
(-7000 4400);
DISPLAY 0.617021 (-7000 4400);
PAINT BLUE (-7000 4400);
FORCEPROP 1 LAST LOCATION C5D5
J 0
(-7000 4650);
DISPLAY 0.617021 (-7000 4650);
PAINT AQUA (-7000 4650);
FORCEPROP 1 LAST VALUE 22.0UF
J 0
(-7000 4600);
DISPLAY 0.617021 (-7000 4600);
PAINT SKYBLUE (-7000 4600);
FORCEPROP 1 LAST TOLERANCE 20%
J 0
(-7000 4500);
DISPLAY 0.617021 (-7000 4500);
PAINT SKYBLUE (-7000 4500);
FORCEPROP 1 LAST VOLTAGE 4V
J 0
(-7000 4550);
DISPLAY 0.617021 (-7000 4550);
PAINT SKYBLUE (-7000 4550);
FORCEPROP 1 LASTPIN (-7050 4600) $PN 1
J 0
(-7040 4580);
DISPLAY 0.617021 (-7040 4580);
PAINT GREEN (-7040 4580);
FORCEPROP 1 LASTPIN (-7050 4400) $PN 2
J 0
(-7040 4380);
DISPLAY 0.617021 (-7040 4380);
PAINT GREEN (-7040 4380);
FORCEPROP 0 LAST GROUP PWR_MLCC_CAP
J 0
(-6995 4302);
DISPLAY 0.638298 (-6995 4302);
PAINT BROWN (-6995 4302);
DISPLAY BOTH (-6995 4302);
FORCEPROP 2 LAST CDS_LOCATION C5D5
J 0
(-7000 4600);
DISPLAY 0.617021 (-7000 4600);
PAINT AQUA (-7000 4600);
DISPLAY INVISIBLE (-7000 4600);
FORCEPROP 2 LAST BOM_COST PROC_SOCKET
J 0
(-7000 4700);
DISPLAY 1.021277 (-7000 4700);
PAINT ORANGE (-7000 4700);
DISPLAY INVISIBLE (-7000 4700);
FORCEPROP 2 LAST CDS_LIB dev_discrete
J 0
(-7050 4500);
PAINT ORANGE (-7050 4500);
DISPLAY INVISIBLE (-7050 4500);
FORCEPROP 2 LAST CDS_SEC 1
J 0
(-7000 4700);
PAINT MONO (-7000 4700);
DISPLAY INVISIBLE (-7000 4700);
FORCEPROP 2 LAST $SEC 1
J 0
(-7000 4700);
PAINT MONO (-7000 4700);
DISPLAY INVISIBLE (-7000 4700);
FORCEPROP 1 LAST PATH I125
J 0
(-7000 4650);
DISPLAY 0.978723 (-7000 4650);
PAINT WHITE (-7000 4650);
DISPLAY INVISIBLE (-7000 4650);
FORCEPROP 2 LAST ROOM PVCCIN_CPU0_DECAP_VR
J 0
(-7000 4650);
DISPLAY 1.021277 (-7000 4650);
PAINT ORANGE (-7000 4650);
DISPLAY INVISIBLE (-7000 4650);
FORCEADD CAP_A..1
(-7050 3800);
FORCEPROP 0 LAST GROUP PWR_MLCC_CAP
J 0
(-6995 3602);
DISPLAY 0.638298 (-6995 3602);
PAINT BROWN (-6995 3602);
DISPLAY BOTH (-6995 3602);
FORCEPROP 1 LAST PART_NUMBER E15431-004
J 0
(-7000 3700);
DISPLAY 0.617021 (-7000 3700);
PAINT BLUE (-7000 3700);
FORCEPROP 1 LASTPIN (-7050 3700) $PN 2
J 0
(-7040 3680);
DISPLAY 0.617021 (-7040 3680);
PAINT GREEN (-7040 3680);
FORCEPROP 1 LAST MATERIAL X6S
J 0
(-7000 3750);
DISPLAY 0.617021 (-7000 3750);
PAINT SKYBLUE (-7000 3750);
FORCEPROP 1 LAST TOLERANCE 20%
J 0
(-7000 3800);
DISPLAY 0.617021 (-7000 3800);
PAINT SKYBLUE (-7000 3800);
FORCEPROP 1 LASTPIN (-7050 3900) $PN 1
J 0
(-7040 3880);
DISPLAY 0.617021 (-7040 3880);
PAINT GREEN (-7040 3880);
FORCEPROP 1 LAST PACK_TYPE 0603V
J 0
(-7000 3650);
DISPLAY 0.617021 (-7000 3650);
PAINT SKYBLUE (-7000 3650);
FORCEPROP 1 LAST LOCATION C5D19
J 0
(-7000 3950);
DISPLAY 0.617021 (-7000 3950);
PAINT AQUA (-7000 3950);
FORCEPROP 1 LAST VALUE 22.0UF
J 0
(-7000 3900);
DISPLAY 0.617021 (-7000 3900);
PAINT SKYBLUE (-7000 3900);
FORCEPROP 1 LAST VOLTAGE 4V
J 0
(-7000 3850);
DISPLAY 0.617021 (-7000 3850);
PAINT SKYBLUE (-7000 3850);
FORCEPROP 2 LAST CDS_LOCATION C5D19
J 0
(-7000 3900);
DISPLAY 0.617021 (-7000 3900);
PAINT AQUA (-7000 3900);
DISPLAY INVISIBLE (-7000 3900);
FORCEPROP 2 LAST BOM_COST PROC_SOCKET
J 0
(-7000 4000);
DISPLAY 1.021277 (-7000 4000);
PAINT ORANGE (-7000 4000);
DISPLAY INVISIBLE (-7000 4000);
FORCEPROP 2 LAST CDS_LIB dev_discrete
J 0
(-7050 3800);
PAINT ORANGE (-7050 3800);
DISPLAY INVISIBLE (-7050 3800);
FORCEPROP 2 LAST CDS_SEC 1
J 0
(-7000 4000);
PAINT MONO (-7000 4000);
DISPLAY INVISIBLE (-7000 4000);
FORCEPROP 2 LAST $SEC 1
J 0
(-7000 4000);
PAINT MONO (-7000 4000);
DISPLAY INVISIBLE (-7000 4000);
FORCEPROP 1 LAST PATH I128
J 0
(-7000 3950);
DISPLAY 0.978723 (-7000 3950);
PAINT WHITE (-7000 3950);
DISPLAY INVISIBLE (-7000 3950);
FORCEPROP 2 LAST ROOM PVCCIN_CPU0_DECAP_VR
J 0
(-7000 3950);
DISPLAY 1.021277 (-7000 3950);
PAINT ORANGE (-7000 3950);
DISPLAY INVISIBLE (-7000 3950);
FORCEADD CAP_A..1
(-5950 3150);
FORCEPROP 1 LAST PART_NUMBER E15431-004
J 0
(-5900 3050);
DISPLAY 0.617021 (-5900 3050);
PAINT BLUE (-5900 3050);
FORCEPROP 1 LAST VOLTAGE 4V
J 0
(-5900 3200);
DISPLAY 0.617021 (-5900 3200);
PAINT SKYBLUE (-5900 3200);
FORCEPROP 1 LAST TOLERANCE 20%
J 0
(-5900 3150);
DISPLAY 0.617021 (-5900 3150);
PAINT SKYBLUE (-5900 3150);
FORCEPROP 1 LAST MATERIAL X6S
J 0
(-5900 3100);
DISPLAY 0.617021 (-5900 3100);
PAINT SKYBLUE (-5900 3100);
FORCEPROP 1 LASTPIN (-5950 3250) $PN 1
J 0
(-5940 3230);
DISPLAY 0.617021 (-5940 3230);
PAINT GREEN (-5940 3230);
FORCEPROP 1 LASTPIN (-5950 3050) $PN 2
J 0
(-5940 3030);
DISPLAY 0.617021 (-5940 3030);
PAINT GREEN (-5940 3030);
FORCEPROP 1 LAST VALUE 22.0UF
J 0
(-5900 3250);
DISPLAY 0.617021 (-5900 3250);
PAINT SKYBLUE (-5900 3250);
FORCEPROP 1 LAST LOCATION C5D43
J 0
(-5900 3300);
DISPLAY 0.617021 (-5900 3300);
PAINT AQUA (-5900 3300);
FORCEPROP 0 LAST GROUP PWR_MLCC_CAP
J 0
(-5895 2952);
DISPLAY 0.638298 (-5895 2952);
PAINT BROWN (-5895 2952);
DISPLAY BOTH (-5895 2952);
FORCEPROP 1 LAST PACK_TYPE 0603V
J 0
(-5900 3000);
DISPLAY 0.617021 (-5900 3000);
PAINT SKYBLUE (-5900 3000);
FORCEPROP 2 LAST CDS_LOCATION C5D43
J 0
(-5900 3250);
DISPLAY 0.617021 (-5900 3250);
PAINT AQUA (-5900 3250);
DISPLAY INVISIBLE (-5900 3250);
FORCEPROP 2 LAST BOM_COST PROC_SOCKET
J 0
(-5900 3350);
DISPLAY 1.021277 (-5900 3350);
PAINT ORANGE (-5900 3350);
DISPLAY INVISIBLE (-5900 3350);
FORCEPROP 2 LAST CDS_LIB dev_discrete
J 0
(-5950 3150);
PAINT ORANGE (-5950 3150);
DISPLAY INVISIBLE (-5950 3150);
FORCEPROP 2 LAST CDS_SEC 1
J 0
(-5900 3350);
PAINT MONO (-5900 3350);
DISPLAY INVISIBLE (-5900 3350);
FORCEPROP 2 LAST $SEC 1
J 0
(-5900 3350);
PAINT MONO (-5900 3350);
DISPLAY INVISIBLE (-5900 3350);
FORCEPROP 1 LAST PATH I131
J 0
(-5900 3300);
DISPLAY 0.978723 (-5900 3300);
PAINT WHITE (-5900 3300);
DISPLAY INVISIBLE (-5900 3300);
FORCEPROP 2 LAST ROOM PVCCIN_CPU0_DECAP_VR
J 0
(-5900 3300);
DISPLAY 1.021277 (-5900 3300);
PAINT ORANGE (-5900 3300);
DISPLAY INVISIBLE (-5900 3300);
FORCEADD CAP_A..1
(-6650 3100);
FORCEPROP 1 LASTPIN (-6650 3000) $PN 2
J 0
(-6640 2980);
DISPLAY 0.617021 (-6640 2980);
PAINT GREEN (-6640 2980);
FORCEPROP 1 LASTPIN (-6650 3200) $PN 1
J 0
(-6640 3180);
DISPLAY 0.617021 (-6640 3180);
PAINT GREEN (-6640 3180);
FORCEPROP 1 LAST MATERIAL X6S
J 0
(-6600 3050);
DISPLAY 0.617021 (-6600 3050);
PAINT SKYBLUE (-6600 3050);
FORCEPROP 1 LAST TOLERANCE 20%
J 0
(-6600 3100);
DISPLAY 0.617021 (-6600 3100);
PAINT SKYBLUE (-6600 3100);
FORCEPROP 1 LAST VOLTAGE 4V
J 0
(-6600 3150);
DISPLAY 0.617021 (-6600 3150);
PAINT SKYBLUE (-6600 3150);
FORCEPROP 1 LAST PACK_TYPE 0603V
J 0
(-6600 2950);
DISPLAY 0.617021 (-6600 2950);
PAINT SKYBLUE (-6600 2950);
FORCEPROP 1 LAST LOCATION C5D15
J 0
(-6600 3250);
DISPLAY 0.617021 (-6600 3250);
PAINT AQUA (-6600 3250);
FORCEPROP 1 LAST VALUE 22.0UF
J 0
(-6600 3200);
DISPLAY 0.617021 (-6600 3200);
PAINT SKYBLUE (-6600 3200);
FORCEPROP 1 LAST PART_NUMBER E15431-004
J 0
(-6600 3000);
DISPLAY 0.617021 (-6600 3000);
PAINT BLUE (-6600 3000);
FORCEPROP 0 LAST GROUP PWR_MLCC_CAP
J 0
(-6595 2902);
DISPLAY 0.638298 (-6595 2902);
PAINT BROWN (-6595 2902);
DISPLAY BOTH (-6595 2902);
FORCEPROP 2 LAST ROOM PVCCIN_CPU0_DECAP_VR
J 0
(-6600 3250);
DISPLAY 1.021277 (-6600 3250);
PAINT ORANGE (-6600 3250);
DISPLAY INVISIBLE (-6600 3250);
FORCEPROP 1 LAST PATH I132
J 0
(-6600 3250);
DISPLAY 0.978723 (-6600 3250);
PAINT WHITE (-6600 3250);
DISPLAY INVISIBLE (-6600 3250);
FORCEPROP 2 LAST $SEC 1
J 0
(-6600 3300);
PAINT MONO (-6600 3300);
DISPLAY INVISIBLE (-6600 3300);
FORCEPROP 2 LAST CDS_SEC 1
J 0
(-6600 3300);
PAINT MONO (-6600 3300);
DISPLAY INVISIBLE (-6600 3300);
FORCEPROP 2 LAST CDS_LIB dev_discrete
J 0
(-6650 3100);
PAINT ORANGE (-6650 3100);
DISPLAY INVISIBLE (-6650 3100);
FORCEPROP 2 LAST BOM_COST PROC_SOCKET
J 0
(-6600 3300);
DISPLAY 1.021277 (-6600 3300);
PAINT ORANGE (-6600 3300);
DISPLAY INVISIBLE (-6600 3300);
FORCEPROP 2 LAST CDS_LOCATION C5D15
J 0
(-6600 3200);
DISPLAY 0.617021 (-6600 3200);
PAINT AQUA (-6600 3200);
DISPLAY INVISIBLE (-6600 3200);
FORCEADD GND..1
(-7750 2825);
FORCEPROP 3 LASTPIN (-7750 2875) SIG_NAME GND\g
J 0
(-7740 2885);
DISPLAY 0.659574 (-7740 2885);
PAINT MONO (-7740 2885);
DISPLAY INVISIBLE (-7740 2885);
FORCEPROP 1 LAST VOLTAGE 0
J 0
(-7750 2825);
PAINT SKYBLUE (-7750 2825);
DISPLAY INVISIBLE (-7750 2825);
FORCEPROP 1 LAST SIZE 1B
J 0
(-7675 2775);
DISPLAY 0.893617 (-7675 2775);
PAINT GREEN (-7675 2775);
DISPLAY INVISIBLE (-7675 2775);
FORCEPROP 2 LAST CDS_LIB mstr_symbols
J 0
(-7750 2825);
PAINT ORANGE (-7750 2825);
DISPLAY INVISIBLE (-7750 2825);
FORCEPROP 1 LAST BODY_TYPE PLUMBING
J 0
(-7795 2782);
DISPLAY 0.340426 (-7795 2782);
PAINT GREEN (-7795 2782);
DISPLAY INVISIBLE (-7795 2782);
FORCEPROP 1 LAST PATH I133
J 0
(-7675 2825);
DISPLAY 0.872340 (-7675 2825);
PAINT AQUA (-7675 2825);
DISPLAY INVISIBLE (-7675 2825);
FORCEPROP 1 LAST HDL_POWER GND
J 0
(-7750 2975);
DISPLAY 0.893617 (-7750 2975);
PAINT GREEN (-7750 2975);
DISPLAY INVISIBLE (-7750 2975);
FORCEADD CAP_A..1
(-6950 3100);
FORCEPROP 1 LASTPIN (-6950 3200) $PN 1
J 0
(-6940 3180);
DISPLAY 0.617021 (-6940 3180);
PAINT GREEN (-6940 3180);
FORCEPROP 1 LASTPIN (-6950 3000) $PN 2
J 0
(-6940 2980);
DISPLAY 0.617021 (-6940 2980);
PAINT GREEN (-6940 2980);
FORCEPROP 1 LAST MATERIAL X6S
J 0
(-6900 3050);
DISPLAY 0.617021 (-6900 3050);
PAINT SKYBLUE (-6900 3050);
FORCEPROP 1 LAST TOLERANCE 20%
J 0
(-6900 3100);
DISPLAY 0.617021 (-6900 3100);
PAINT SKYBLUE (-6900 3100);
FORCEPROP 1 LAST VOLTAGE 4V
J 0
(-6900 3150);
DISPLAY 0.617021 (-6900 3150);
PAINT SKYBLUE (-6900 3150);
FORCEPROP 1 LAST VALUE 22.0UF
J 0
(-6900 3200);
DISPLAY 0.617021 (-6900 3200);
PAINT SKYBLUE (-6900 3200);
FORCEPROP 1 LAST PART_NUMBER E15431-004
J 0
(-6900 3000);
DISPLAY 0.617021 (-6900 3000);
PAINT BLUE (-6900 3000);
FORCEPROP 1 LAST PACK_TYPE 0603V
J 0
(-6900 2950);
DISPLAY 0.617021 (-6900 2950);
PAINT SKYBLUE (-6900 2950);
FORCEPROP 1 LAST LOCATION C5D18
J 0
(-6900 3250);
DISPLAY 0.617021 (-6900 3250);
PAINT AQUA (-6900 3250);
FORCEPROP 0 LAST GROUP PWR_MLCC_CAP
J 0
(-6895 2852);
DISPLAY 0.638298 (-6895 2852);
PAINT BROWN (-6895 2852);
DISPLAY BOTH (-6895 2852);
FORCEPROP 2 LAST CDS_LOCATION C5D18
J 0
(-6900 3200);
DISPLAY 0.617021 (-6900 3200);
PAINT AQUA (-6900 3200);
DISPLAY INVISIBLE (-6900 3200);
FORCEPROP 2 LAST BOM_COST PROC_SOCKET
J 0
(-6900 3300);
DISPLAY 1.021277 (-6900 3300);
PAINT ORANGE (-6900 3300);
DISPLAY INVISIBLE (-6900 3300);
FORCEPROP 2 LAST CDS_LIB dev_discrete
J 0
(-6950 3100);
PAINT ORANGE (-6950 3100);
DISPLAY INVISIBLE (-6950 3100);
FORCEPROP 2 LAST CDS_SEC 1
J 0
(-6900 3300);
PAINT MONO (-6900 3300);
DISPLAY INVISIBLE (-6900 3300);
FORCEPROP 2 LAST $SEC 1
J 0
(-6900 3300);
PAINT MONO (-6900 3300);
DISPLAY INVISIBLE (-6900 3300);
FORCEPROP 1 LAST PATH I134
J 0
(-6900 3250);
DISPLAY 0.978723 (-6900 3250);
PAINT WHITE (-6900 3250);
DISPLAY INVISIBLE (-6900 3250);
FORCEPROP 2 LAST ROOM PVCCIN_CPU0_DECAP_VR
J 0
(-6900 3250);
DISPLAY 1.021277 (-6900 3250);
PAINT ORANGE (-6900 3250);
DISPLAY INVISIBLE (-6900 3250);
FORCEADD CAP_A..1
(-7250 3100);
FORCEPROP 0 LAST GROUP PWR_MLCC_CAP
J 0
(-7195 2902);
DISPLAY 0.638298 (-7195 2902);
PAINT BROWN (-7195 2902);
DISPLAY BOTH (-7195 2902);
FORCEPROP 1 LAST PART_NUMBER E15431-004
J 0
(-7200 3000);
DISPLAY 0.617021 (-7200 3000);
PAINT BLUE (-7200 3000);
FORCEPROP 1 LAST PACK_TYPE 0603V
J 0
(-7200 2950);
DISPLAY 0.617021 (-7200 2950);
PAINT SKYBLUE (-7200 2950);
FORCEPROP 1 LASTPIN (-7250 3000) $PN 2
J 0
(-7240 2980);
DISPLAY 0.617021 (-7240 2980);
PAINT GREEN (-7240 2980);
FORCEPROP 1 LASTPIN (-7250 3200) $PN 1
J 0
(-7240 3180);
DISPLAY 0.617021 (-7240 3180);
PAINT GREEN (-7240 3180);
FORCEPROP 1 LAST VOLTAGE 4V
J 0
(-7200 3150);
DISPLAY 0.617021 (-7200 3150);
PAINT SKYBLUE (-7200 3150);
FORCEPROP 1 LAST LOCATION C5D42
J 0
(-7200 3250);
DISPLAY 0.617021 (-7200 3250);
PAINT AQUA (-7200 3250);
FORCEPROP 1 LAST VALUE 22.0UF
J 0
(-7200 3200);
DISPLAY 0.617021 (-7200 3200);
PAINT SKYBLUE (-7200 3200);
FORCEPROP 1 LAST MATERIAL X6S
J 0
(-7200 3050);
DISPLAY 0.617021 (-7200 3050);
PAINT SKYBLUE (-7200 3050);
FORCEPROP 1 LAST TOLERANCE 20%
J 0
(-7200 3100);
DISPLAY 0.617021 (-7200 3100);
PAINT SKYBLUE (-7200 3100);
FORCEPROP 2 LAST ROOM PVCCIN_CPU0_DECAP_VR
J 0
(-7200 3250);
DISPLAY 1.021277 (-7200 3250);
PAINT ORANGE (-7200 3250);
DISPLAY INVISIBLE (-7200 3250);
FORCEPROP 1 LAST PATH I135
J 0
(-7200 3250);
DISPLAY 0.978723 (-7200 3250);
PAINT WHITE (-7200 3250);
DISPLAY INVISIBLE (-7200 3250);
FORCEPROP 2 LAST $SEC 1
J 0
(-7200 3300);
PAINT MONO (-7200 3300);
DISPLAY INVISIBLE (-7200 3300);
FORCEPROP 2 LAST CDS_SEC 1
J 0
(-7200 3300);
PAINT MONO (-7200 3300);
DISPLAY INVISIBLE (-7200 3300);
FORCEPROP 2 LAST CDS_LIB dev_discrete
J 0
(-7250 3100);
PAINT ORANGE (-7250 3100);
DISPLAY INVISIBLE (-7250 3100);
FORCEPROP 2 LAST BOM_COST PROC_SOCKET
J 0
(-7200 3300);
DISPLAY 1.021277 (-7200 3300);
PAINT ORANGE (-7200 3300);
DISPLAY INVISIBLE (-7200 3300);
FORCEPROP 2 LAST CDS_LOCATION C5D42
J 0
(-7200 3200);
DISPLAY 0.617021 (-7200 3200);
PAINT AQUA (-7200 3200);
DISPLAY INVISIBLE (-7200 3200);
FORCEADD PVCCIN_CPU0..1
(-7750 4800);
FORCEPROP 3 LASTPIN (-7750 4750) SIG_NAME PVCCIN_CPU0\g
J 0
(-7740 4760);
DISPLAY 0.659574 (-7740 4760);
PAINT MONO (-7740 4760);
DISPLAY INVISIBLE (-7740 4760);
FORCEPROP 1 LAST VOLTAGE 2.0V
J 0
(-7795 4757);
DISPLAY 0.340426 (-7795 4757);
PAINT SKYBLUE (-7795 4757);
DISPLAY INVISIBLE (-7795 4757);
FORCEPROP 2 LAST CDS_LIB mstr_symbols
J 0
(-7750 4800);
PAINT ORANGE (-7750 4800);
DISPLAY INVISIBLE (-7750 4800);
FORCEPROP 1 LAST BODY_TYPE PLUMBING
J 0
(-7795 4757);
DISPLAY 0.340426 (-7795 4757);
PAINT GREEN (-7795 4757);
DISPLAY INVISIBLE (-7795 4757);
FORCEPROP 1 LAST PATH I137
J 0
(-7700 4825);
DISPLAY 0.872340 (-7700 4825);
PAINT AQUA (-7700 4825);
DISPLAY INVISIBLE (-7700 4825);
FORCEPROP 1 LAST HDL_POWER PVCCIN_CPU0
J 1
(-7750 4850);
DISPLAY 0.872340 (-7750 4850);
PAINT GREEN (-7750 4850);
DISPLAY INVISIBLE (-7750 4850);
FORCEADD CAP_A..1
(-7750 4500);
FORCEPROP 1 LASTPIN (-7750 4400) $PN 2
J 0
(-7740 4380);
DISPLAY 0.617021 (-7740 4380);
PAINT GREEN (-7740 4380);
FORCEPROP 1 LAST PACK_TYPE 0603V
J 0
(-7700 4350);
DISPLAY 0.617021 (-7700 4350);
PAINT SKYBLUE (-7700 4350);
FORCEPROP 1 LAST PART_NUMBER E15431-004
J 0
(-7700 4400);
DISPLAY 0.617021 (-7700 4400);
PAINT BLUE (-7700 4400);
FORCEPROP 1 LAST MATERIAL X6S
J 0
(-7700 4450);
DISPLAY 0.617021 (-7700 4450);
PAINT SKYBLUE (-7700 4450);
FORCEPROP 1 LAST VALUE 22.0UF
J 0
(-7700 4600);
DISPLAY 0.617021 (-7700 4600);
PAINT SKYBLUE (-7700 4600);
FORCEPROP 1 LASTPIN (-7750 4600) $PN 1
J 0
(-7740 4580);
DISPLAY 0.617021 (-7740 4580);
PAINT GREEN (-7740 4580);
FORCEPROP 1 LAST VOLTAGE 4V
J 0
(-7700 4550);
DISPLAY 0.617021 (-7700 4550);
PAINT SKYBLUE (-7700 4550);
FORCEPROP 1 LAST TOLERANCE 20%
J 0
(-7700 4500);
DISPLAY 0.617021 (-7700 4500);
PAINT SKYBLUE (-7700 4500);
FORCEPROP 1 LAST LOCATION C5D24
J 0
(-7700 4650);
DISPLAY 0.617021 (-7700 4650);
PAINT AQUA (-7700 4650);
FORCEPROP 0 LAST GROUP PWR_MLCC_CAP
J 0
(-7695 4302);
DISPLAY 0.638298 (-7695 4302);
PAINT BROWN (-7695 4302);
DISPLAY BOTH (-7695 4302);
FORCEPROP 2 LAST CDS_LOCATION C5D24
J 0
(-7700 4600);
DISPLAY 0.617021 (-7700 4600);
PAINT AQUA (-7700 4600);
DISPLAY INVISIBLE (-7700 4600);
FORCEPROP 2 LAST BOM_COST PROC_SOCKET
J 0
(-7700 4700);
DISPLAY 1.021277 (-7700 4700);
PAINT ORANGE (-7700 4700);
DISPLAY INVISIBLE (-7700 4700);
FORCEPROP 2 LAST CDS_LIB dev_discrete
J 0
(-7750 4500);
PAINT ORANGE (-7750 4500);
DISPLAY INVISIBLE (-7750 4500);
FORCEPROP 2 LAST CDS_SEC 1
J 0
(-7700 4700);
PAINT MONO (-7700 4700);
DISPLAY INVISIBLE (-7700 4700);
FORCEPROP 2 LAST $SEC 1
J 0
(-7700 4700);
PAINT MONO (-7700 4700);
DISPLAY INVISIBLE (-7700 4700);
FORCEPROP 1 LAST PATH I138
J 0
(-7700 4650);
DISPLAY 0.978723 (-7700 4650);
PAINT WHITE (-7700 4650);
DISPLAY INVISIBLE (-7700 4650);
FORCEPROP 2 LAST ROOM PVCCIN_CPU0_DECAP_VR
J 0
(-7700 4650);
DISPLAY 1.021277 (-7700 4650);
PAINT ORANGE (-7700 4650);
DISPLAY INVISIBLE (-7700 4650);
FORCEADD PVCCIN_CPU0..1
(-7750 4100);
FORCEPROP 3 LASTPIN (-7750 4050) SIG_NAME PVCCIN_CPU0\g
J 0
(-7740 4060);
DISPLAY 0.659574 (-7740 4060);
PAINT MONO (-7740 4060);
DISPLAY INVISIBLE (-7740 4060);
FORCEPROP 1 LAST VOLTAGE 2.0V
J 0
(-7795 4057);
DISPLAY 0.340426 (-7795 4057);
PAINT SKYBLUE (-7795 4057);
DISPLAY INVISIBLE (-7795 4057);
FORCEPROP 2 LAST CDS_LIB mstr_symbols
J 0
(-7750 4100);
PAINT ORANGE (-7750 4100);
DISPLAY INVISIBLE (-7750 4100);
FORCEPROP 1 LAST BODY_TYPE PLUMBING
J 0
(-7795 4057);
DISPLAY 0.340426 (-7795 4057);
PAINT GREEN (-7795 4057);
DISPLAY INVISIBLE (-7795 4057);
FORCEPROP 1 LAST PATH I139
J 0
(-7700 4125);
DISPLAY 0.872340 (-7700 4125);
PAINT AQUA (-7700 4125);
DISPLAY INVISIBLE (-7700 4125);
FORCEPROP 1 LAST HDL_POWER PVCCIN_CPU0
J 1
(-7750 4150);
DISPLAY 0.872340 (-7750 4150);
PAINT GREEN (-7750 4150);
DISPLAY INVISIBLE (-7750 4150);
FORCEADD CAP_A..1
(-7750 3800);
FORCEPROP 0 LAST GROUP PWR_MLCC_CAP
J 0
(-7695 3602);
DISPLAY 0.638298 (-7695 3602);
PAINT BROWN (-7695 3602);
DISPLAY BOTH (-7695 3602);
FORCEPROP 1 LAST PART_NUMBER E15431-004
J 0
(-7700 3700);
DISPLAY 0.617021 (-7700 3700);
PAINT BLUE (-7700 3700);
FORCEPROP 1 LASTPIN (-7750 3700) $PN 2
J 0
(-7740 3680);
DISPLAY 0.617021 (-7740 3680);
PAINT GREEN (-7740 3680);
FORCEPROP 1 LASTPIN (-7750 3900) $PN 1
J 0
(-7740 3880);
DISPLAY 0.617021 (-7740 3880);
PAINT GREEN (-7740 3880);
FORCEPROP 1 LAST LOCATION C5D39
J 0
(-7700 3950);
DISPLAY 0.617021 (-7700 3950);
PAINT AQUA (-7700 3950);
FORCEPROP 1 LAST MATERIAL X6S
J 0
(-7700 3750);
DISPLAY 0.617021 (-7700 3750);
PAINT SKYBLUE (-7700 3750);
FORCEPROP 1 LAST PACK_TYPE 0603V
J 0
(-7700 3650);
DISPLAY 0.617021 (-7700 3650);
PAINT SKYBLUE (-7700 3650);
FORCEPROP 1 LAST VALUE 22.0UF
J 0
(-7700 3900);
DISPLAY 0.617021 (-7700 3900);
PAINT SKYBLUE (-7700 3900);
FORCEPROP 1 LAST VOLTAGE 4V
J 0
(-7700 3850);
DISPLAY 0.617021 (-7700 3850);
PAINT SKYBLUE (-7700 3850);
FORCEPROP 1 LAST TOLERANCE 20%
J 0
(-7700 3800);
DISPLAY 0.617021 (-7700 3800);
PAINT SKYBLUE (-7700 3800);
FORCEPROP 2 LAST CDS_LOCATION C5D39
J 0
(-7700 3900);
DISPLAY 0.617021 (-7700 3900);
PAINT AQUA (-7700 3900);
DISPLAY INVISIBLE (-7700 3900);
FORCEPROP 2 LAST BOM_COST PROC_SOCKET
J 0
(-7700 4000);
DISPLAY 1.021277 (-7700 4000);
PAINT ORANGE (-7700 4000);
DISPLAY INVISIBLE (-7700 4000);
FORCEPROP 2 LAST CDS_LIB dev_discrete
J 0
(-7750 3800);
PAINT ORANGE (-7750 3800);
DISPLAY INVISIBLE (-7750 3800);
FORCEPROP 2 LAST CDS_SEC 1
J 0
(-7700 4000);
PAINT MONO (-7700 4000);
DISPLAY INVISIBLE (-7700 4000);
FORCEPROP 2 LAST $SEC 1
J 0
(-7700 4000);
PAINT MONO (-7700 4000);
DISPLAY INVISIBLE (-7700 4000);
FORCEPROP 1 LAST PATH I140
J 0
(-7700 3950);
DISPLAY 0.978723 (-7700 3950);
PAINT WHITE (-7700 3950);
DISPLAY INVISIBLE (-7700 3950);
FORCEPROP 2 LAST ROOM PVCCIN_CPU0_DECAP_VR
J 0
(-7700 3950);
DISPLAY 1.021277 (-7700 3950);
PAINT ORANGE (-7700 3950);
DISPLAY INVISIBLE (-7700 3950);
FORCEADD PVCCIN_CPU0..1
(-7750 3400);
FORCEPROP 3 LASTPIN (-7750 3350) SIG_NAME PVCCIN_CPU0\g
J 0
(-7740 3360);
DISPLAY 0.659574 (-7740 3360);
PAINT MONO (-7740 3360);
DISPLAY INVISIBLE (-7740 3360);
FORCEPROP 1 LAST HDL_POWER PVCCIN_CPU0
J 1
(-7750 3450);
DISPLAY 0.872340 (-7750 3450);
PAINT GREEN (-7750 3450);
DISPLAY INVISIBLE (-7750 3450);
FORCEPROP 1 LAST PATH I141
J 0
(-7700 3425);
DISPLAY 0.872340 (-7700 3425);
PAINT AQUA (-7700 3425);
DISPLAY INVISIBLE (-7700 3425);
FORCEPROP 1 LAST BODY_TYPE PLUMBING
J 0
(-7795 3357);
DISPLAY 0.340426 (-7795 3357);
PAINT GREEN (-7795 3357);
DISPLAY INVISIBLE (-7795 3357);
FORCEPROP 2 LAST CDS_LIB mstr_symbols
J 0
(-7750 3400);
PAINT ORANGE (-7750 3400);
DISPLAY INVISIBLE (-7750 3400);
FORCEPROP 1 LAST VOLTAGE 2.0V
J 0
(-7795 3357);
DISPLAY 0.340426 (-7795 3357);
PAINT SKYBLUE (-7795 3357);
DISPLAY INVISIBLE (-7795 3357);
FORCEADD CAP_A..1
(-7750 3100);
FORCEPROP 0 LAST GROUP PWR_MLCC_CAP
J 0
(-7695 2902);
DISPLAY 0.638298 (-7695 2902);
PAINT BROWN (-7695 2902);
DISPLAY BOTH (-7695 2902);
FORCEPROP 1 LAST LOCATION C5D44
J 0
(-7700 3250);
DISPLAY 0.617021 (-7700 3250);
PAINT AQUA (-7700 3250);
FORCEPROP 1 LAST VALUE 22.0UF
J 0
(-7700 3200);
DISPLAY 0.617021 (-7700 3200);
PAINT SKYBLUE (-7700 3200);
FORCEPROP 1 LAST VOLTAGE 4V
J 0
(-7700 3150);
DISPLAY 0.617021 (-7700 3150);
PAINT SKYBLUE (-7700 3150);
FORCEPROP 1 LAST TOLERANCE 20%
J 0
(-7700 3100);
DISPLAY 0.617021 (-7700 3100);
PAINT SKYBLUE (-7700 3100);
FORCEPROP 1 LAST MATERIAL X6S
J 0
(-7700 3050);
DISPLAY 0.617021 (-7700 3050);
PAINT SKYBLUE (-7700 3050);
FORCEPROP 1 LAST PART_NUMBER E15431-004
J 0
(-7700 3000);
DISPLAY 0.617021 (-7700 3000);
PAINT BLUE (-7700 3000);
FORCEPROP 1 LAST PACK_TYPE 0603V
J 0
(-7700 2950);
DISPLAY 0.617021 (-7700 2950);
PAINT SKYBLUE (-7700 2950);
FORCEPROP 1 LASTPIN (-7750 3000) $PN 2
J 0
(-7740 2980);
DISPLAY 0.617021 (-7740 2980);
PAINT GREEN (-7740 2980);
FORCEPROP 1 LASTPIN (-7750 3200) $PN 1
J 0
(-7740 3180);
DISPLAY 0.617021 (-7740 3180);
PAINT GREEN (-7740 3180);
FORCEPROP 2 LAST CDS_LOCATION C5D44
J 0
(-7700 3200);
DISPLAY 0.617021 (-7700 3200);
PAINT AQUA (-7700 3200);
DISPLAY INVISIBLE (-7700 3200);
FORCEPROP 2 LAST BOM_COST PROC_SOCKET
J 0
(-7700 3300);
DISPLAY 1.021277 (-7700 3300);
PAINT ORANGE (-7700 3300);
DISPLAY INVISIBLE (-7700 3300);
FORCEPROP 2 LAST CDS_LIB dev_discrete
J 0
(-7750 3100);
PAINT ORANGE (-7750 3100);
DISPLAY INVISIBLE (-7750 3100);
FORCEPROP 2 LAST CDS_SEC 1
J 0
(-7700 3300);
PAINT MONO (-7700 3300);
DISPLAY INVISIBLE (-7700 3300);
FORCEPROP 2 LAST $SEC 1
J 0
(-7700 3300);
PAINT MONO (-7700 3300);
DISPLAY INVISIBLE (-7700 3300);
FORCEPROP 1 LAST PATH I142
J 0
(-7700 3250);
DISPLAY 0.978723 (-7700 3250);
PAINT WHITE (-7700 3250);
DISPLAY INVISIBLE (-7700 3250);
FORCEPROP 2 LAST ROOM PVCCIN_CPU0_DECAP_VR
J 0
(-7700 3250);
DISPLAY 1.021277 (-7700 3250);
PAINT ORANGE (-7700 3250);
DISPLAY INVISIBLE (-7700 3250);
FORCEADD VCC_CORE..1
(-3550 4725);
FORCEPROP 3 LASTPIN (-3550 4675) SIG_NAME PVCCMCP_CPU0\g
J 0
(-3540 4685);
DISPLAY 0.659574 (-3540 4685);
PAINT MONO (-3540 4685);
DISPLAY INVISIBLE (-3540 4685);
FORCEPROP 1 LAST HDL_POWER PVCCMCP_CPU0
J 1
(-3550 4775);
DISPLAY 0.617021 (-3550 4775);
PAINT GREEN (-3550 4775);
FORCEPROP 1 LAST PATH I144
J 0
(-3500 4750);
DISPLAY 0.872340 (-3500 4750);
PAINT AQUA (-3500 4750);
DISPLAY INVISIBLE (-3500 4750);
FORCEPROP 2 LAST CDS_LIB mstr_symbols
J 0
(-3550 4725);
PAINT ORANGE (-3550 4725);
DISPLAY INVISIBLE (-3550 4725);
FORCEADD CAP_A..1
(-2850 3800);
FORCEPROP 0 LAST GROUP PWR_MLCC_CAP
J 0
(-2795 3552);
DISPLAY 0.638298 (-2795 3552);
PAINT BROWN (-2795 3552);
DISPLAY BOTH (-2795 3552);
FORCEPROP 1 LAST PART_NUMBER E15431-004
J 0
(-2800 3700);
DISPLAY 0.617021 (-2800 3700);
PAINT BLUE (-2800 3700);
FORCEPROP 1 LAST MATERIAL X6S
J 0
(-2800 3750);
DISPLAY 0.617021 (-2800 3750);
PAINT SKYBLUE (-2800 3750);
FORCEPROP 1 LAST VOLTAGE 4V
J 0
(-2800 3850);
DISPLAY 0.617021 (-2800 3850);
PAINT SKYBLUE (-2800 3850);
FORCEPROP 1 LAST TOLERANCE 20%
J 0
(-2800 3800);
DISPLAY 0.617021 (-2800 3800);
PAINT SKYBLUE (-2800 3800);
FORCEPROP 1 LASTPIN (-2850 3700) $PN 2
J 0
(-2840 3680);
DISPLAY 0.617021 (-2840 3680);
PAINT ORANGE (-2840 3680);
FORCEPROP 1 LAST PACK_TYPE 0603V
J 0
(-2800 3650);
DISPLAY 0.617021 (-2800 3650);
PAINT SKYBLUE (-2800 3650);
FORCEPROP 1 LASTPIN (-2850 3900) $PN 1
J 0
(-2840 3880);
DISPLAY 0.617021 (-2840 3880);
PAINT ORANGE (-2840 3880);
FORCEPROP 1 LAST VALUE 22.0UF
J 0
(-2800 3900);
DISPLAY 0.617021 (-2800 3900);
PAINT SKYBLUE (-2800 3900);
FORCEPROP 1 LAST LOCATION C6D9
J 0
(-2800 3950);
DISPLAY 0.617021 (-2800 3950);
PAINT AQUA (-2800 3950);
FORCEPROP 0 LAST ROOM PVCCIN_CPU0_DECAP_VR
J 0
(-2800 3950);
DISPLAY 1.021277 (-2800 3950);
PAINT ORANGE (-2800 3950);
DISPLAY INVISIBLE (-2800 3950);
FORCEPROP 1 LAST PATH I145
J 0
(-2800 3950);
DISPLAY 0.978723 (-2800 3950);
PAINT WHITE (-2800 3950);
DISPLAY INVISIBLE (-2800 3950);
FORCEPROP 2 LAST $SEC 1
J 0
(-2800 4000);
PAINT MONO (-2800 4000);
DISPLAY INVISIBLE (-2800 4000);
FORCEPROP 2 LAST CDS_SEC 1
J 0
(-2800 4000);
PAINT MONO (-2800 4000);
DISPLAY INVISIBLE (-2800 4000);
FORCEPROP 2 LAST CDS_LIB dev_discrete
J 0
(-2850 3800);
PAINT ORANGE (-2850 3800);
DISPLAY INVISIBLE (-2850 3800);
FORCEPROP 2 LAST CDS_LOCATION C6D9
J 0
(-2800 3900);
DISPLAY 0.617021 (-2800 3900);
PAINT AQUA (-2800 3900);
DISPLAY INVISIBLE (-2800 3900);
FORCEADD CAP_A..1
(-3100 3800);
FORCEPROP 0 LAST GROUP PWR_MLCC_CAP
J 0
(-3045 3602);
DISPLAY 0.638298 (-3045 3602);
PAINT BROWN (-3045 3602);
DISPLAY BOTH (-3045 3602);
FORCEPROP 1 LAST PACK_TYPE 0603V
J 0
(-3050 3650);
DISPLAY 0.617021 (-3050 3650);
PAINT SKYBLUE (-3050 3650);
FORCEPROP 1 LAST PART_NUMBER E15431-004
J 0
(-3050 3700);
DISPLAY 0.617021 (-3050 3700);
PAINT BLUE (-3050 3700);
FORCEPROP 1 LAST TOLERANCE 20%
J 0
(-3050 3800);
DISPLAY 0.617021 (-3050 3800);
PAINT SKYBLUE (-3050 3800);
FORCEPROP 1 LASTPIN (-3100 3900) $PN 1
J 0
(-3090 3880);
DISPLAY 0.617021 (-3090 3880);
PAINT ORANGE (-3090 3880);
FORCEPROP 1 LAST MATERIAL X6S
J 0
(-3050 3750);
DISPLAY 0.617021 (-3050 3750);
PAINT SKYBLUE (-3050 3750);
FORCEPROP 1 LAST VOLTAGE 4V
J 0
(-3050 3850);
DISPLAY 0.617021 (-3050 3850);
PAINT SKYBLUE (-3050 3850);
FORCEPROP 1 LASTPIN (-3100 3700) $PN 2
J 0
(-3090 3680);
DISPLAY 0.617021 (-3090 3680);
PAINT ORANGE (-3090 3680);
FORCEPROP 1 LAST VALUE 22.0UF
J 0
(-3050 3900);
DISPLAY 0.617021 (-3050 3900);
PAINT SKYBLUE (-3050 3900);
FORCEPROP 1 LAST LOCATION C6D10
J 0
(-3050 3950);
DISPLAY 0.617021 (-3050 3950);
PAINT AQUA (-3050 3950);
FORCEPROP 0 LAST ROOM PVCCIN_CPU0_DECAP_VR
J 0
(-3050 3950);
DISPLAY 1.021277 (-3050 3950);
PAINT ORANGE (-3050 3950);
DISPLAY INVISIBLE (-3050 3950);
FORCEPROP 1 LAST PATH I147
J 0
(-3050 3950);
DISPLAY 0.978723 (-3050 3950);
PAINT WHITE (-3050 3950);
DISPLAY INVISIBLE (-3050 3950);
FORCEPROP 2 LAST $SEC 1
J 0
(-3050 4000);
PAINT MONO (-3050 4000);
DISPLAY INVISIBLE (-3050 4000);
FORCEPROP 2 LAST CDS_SEC 1
J 0
(-3050 4000);
PAINT MONO (-3050 4000);
DISPLAY INVISIBLE (-3050 4000);
FORCEPROP 2 LAST CDS_LIB dev_discrete
J 0
(-3100 3800);
PAINT ORANGE (-3100 3800);
DISPLAY INVISIBLE (-3100 3800);
FORCEPROP 2 LAST CDS_LOCATION C6D10
J 0
(-3050 3900);
DISPLAY 0.617021 (-3050 3900);
PAINT AQUA (-3050 3900);
DISPLAY INVISIBLE (-3050 3900);
FORCEADD CAP_A..1
(-2300 4500);
FORCEPROP 1 LASTPIN (-2300 4600) $PN 1
J 0
(-2290 4580);
DISPLAY 0.617021 (-2290 4580);
PAINT ORANGE (-2290 4580);
FORCEPROP 1 LAST PACK_TYPE 0603V
J 0
(-2250 4300);
DISPLAY 0.617021 (-2250 4300);
PAINT SKYBLUE (-2250 4300);
FORCEPROP 1 LASTPIN (-2300 4400) $PN 2
J 0
(-2290 4380);
DISPLAY 0.617021 (-2290 4380);
PAINT ORANGE (-2290 4380);
FORCEPROP 1 LAST MATERIAL X6S
J 0
(-2250 4400);
DISPLAY 0.617021 (-2250 4400);
PAINT SKYBLUE (-2250 4400);
FORCEPROP 1 LAST TOLERANCE 20%
J 0
(-2250 4450);
DISPLAY 0.617021 (-2250 4450);
PAINT SKYBLUE (-2250 4450);
FORCEPROP 1 LAST VOLTAGE 4V
J 0
(-2250 4500);
DISPLAY 0.617021 (-2250 4500);
PAINT SKYBLUE (-2250 4500);
FORCEPROP 1 LAST LOCATION C5D36
J 0
(-2250 4600);
DISPLAY 0.617021 (-2250 4600);
PAINT AQUA (-2250 4600);
FORCEPROP 1 LAST PART_NUMBER E15431-004
J 0
(-2250 4350);
DISPLAY 0.617021 (-2250 4350);
PAINT BLUE (-2250 4350);
FORCEPROP 1 LAST VALUE 22.0UF
J 0
(-2250 4550);
DISPLAY 0.617021 (-2250 4550);
PAINT SKYBLUE (-2250 4550);
FORCEPROP 0 LAST GROUP PWR_MCP_CAP
J 0
(-2250 4200);
DISPLAY 0.638298 (-2250 4200);
PAINT BROWN (-2250 4200);
DISPLAY BOTH (-2250 4200);
FORCEPROP 2 LAST ROOM PVCCIN_CPU0_DECAP_VR
J 0
(-2250 4650);
DISPLAY 1.021277 (-2250 4650);
PAINT ORANGE (-2250 4650);
DISPLAY INVISIBLE (-2250 4650);
FORCEPROP 1 LAST PATH I151
J 0
(-2250 4650);
DISPLAY 0.978723 (-2250 4650);
PAINT WHITE (-2250 4650);
DISPLAY INVISIBLE (-2250 4650);
FORCEPROP 2 LAST $SEC 1
J 0
(-2250 4700);
PAINT MONO (-2250 4700);
DISPLAY INVISIBLE (-2250 4700);
FORCEPROP 2 LAST CDS_SEC 1
J 0
(-2250 4700);
PAINT MONO (-2250 4700);
DISPLAY INVISIBLE (-2250 4700);
FORCEPROP 2 LAST CDS_LIB dev_discrete
J 0
(-2300 4500);
PAINT ORANGE (-2300 4500);
DISPLAY INVISIBLE (-2300 4500);
FORCEPROP 2 LAST BOM_COST PROC_SOCKET
J 0
(-2250 4700);
DISPLAY 1.021277 (-2250 4700);
PAINT ORANGE (-2250 4700);
DISPLAY INVISIBLE (-2250 4700);
FORCEPROP 2 LAST CDS_LOCATION C5D36
J 0
(-2250 4600);
DISPLAY 0.617021 (-2250 4600);
PAINT AQUA (-2250 4600);
DISPLAY INVISIBLE (-2250 4600);
FORCEADD CAP_A..1
(-2050 4500);
FORCEPROP 1 LAST VOLTAGE 4V
J 0
(-2000 4500);
DISPLAY 0.617021 (-2000 4500);
PAINT SKYBLUE (-2000 4500);
FORCEPROP 1 LAST TOLERANCE 20%
J 0
(-2000 4450);
DISPLAY 0.617021 (-2000 4450);
PAINT SKYBLUE (-2000 4450);
FORCEPROP 1 LAST PART_NUMBER E15431-004
J 0
(-2000 4350);
DISPLAY 0.617021 (-2000 4350);
PAINT BLUE (-2000 4350);
FORCEPROP 1 LAST PACK_TYPE 0603V
J 0
(-2000 4300);
DISPLAY 0.617021 (-2000 4300);
PAINT SKYBLUE (-2000 4300);
FORCEPROP 1 LASTPIN (-2050 4600) $PN 1
J 0
(-2040 4580);
DISPLAY 0.617021 (-2040 4580);
PAINT ORANGE (-2040 4580);
FORCEPROP 1 LASTPIN (-2050 4400) $PN 2
J 0
(-2040 4380);
DISPLAY 0.617021 (-2040 4380);
PAINT ORANGE (-2040 4380);
FORCEPROP 1 LAST LOCATION C5D49
J 0
(-2000 4600);
DISPLAY 0.617021 (-2000 4600);
PAINT AQUA (-2000 4600);
FORCEPROP 1 LAST MATERIAL X6S
J 0
(-2000 4400);
DISPLAY 0.617021 (-2000 4400);
PAINT SKYBLUE (-2000 4400);
FORCEPROP 1 LAST VALUE 22.0UF
J 0
(-2000 4550);
DISPLAY 0.617021 (-2000 4550);
PAINT SKYBLUE (-2000 4550);
FORCEPROP 0 LAST GROUP PWR_MCP_CAP
J 0
(-2000 4250);
DISPLAY 0.638298 (-2000 4250);
PAINT BROWN (-2000 4250);
DISPLAY BOTH (-2000 4250);
FORCEPROP 2 LAST CDS_LOCATION C5D49
J 0
(-2000 4600);
DISPLAY 0.617021 (-2000 4600);
PAINT AQUA (-2000 4600);
DISPLAY INVISIBLE (-2000 4600);
FORCEPROP 2 LAST BOM_COST PROC_SOCKET
J 0
(-2000 4700);
DISPLAY 1.021277 (-2000 4700);
PAINT ORANGE (-2000 4700);
DISPLAY INVISIBLE (-2000 4700);
FORCEPROP 2 LAST CDS_LIB dev_discrete
J 0
(-2050 4500);
PAINT ORANGE (-2050 4500);
DISPLAY INVISIBLE (-2050 4500);
FORCEPROP 2 LAST CDS_SEC 1
J 0
(-2000 4700);
PAINT MONO (-2000 4700);
DISPLAY INVISIBLE (-2000 4700);
FORCEPROP 2 LAST $SEC 1
J 0
(-2000 4700);
PAINT MONO (-2000 4700);
DISPLAY INVISIBLE (-2000 4700);
FORCEPROP 1 LAST PATH I152
J 0
(-2000 4650);
DISPLAY 0.978723 (-2000 4650);
PAINT WHITE (-2000 4650);
DISPLAY INVISIBLE (-2000 4650);
FORCEPROP 2 LAST ROOM PVCCIN_CPU0_DECAP_VR
J 0
(-2000 4650);
DISPLAY 1.021277 (-2000 4650);
PAINT ORANGE (-2000 4650);
DISPLAY INVISIBLE (-2000 4650);
FORCEADD CAP_A..1
(-550 4500);
FORCEPROP 1 LAST PACK_TYPE 0603V
J 0
(-500 4300);
DISPLAY 0.617021 (-500 4300);
PAINT SKYBLUE (-500 4300);
FORCEPROP 1 LAST PART_NUMBER E15431-004
J 0
(-500 4350);
DISPLAY 0.617021 (-500 4350);
PAINT BLUE (-500 4350);
FORCEPROP 0 LAST GROUP PWR_MCP_CAP
J 0
(-500 4250);
DISPLAY 0.638298 (-500 4250);
PAINT BROWN (-500 4250);
DISPLAY BOTH (-500 4250);
FORCEPROP 1 LAST LOCATION C5D22
J 0
(-500 4600);
DISPLAY 0.617021 (-500 4600);
PAINT AQUA (-500 4600);
FORCEPROP 1 LAST VALUE 22.0UF
J 0
(-500 4550);
DISPLAY 0.617021 (-500 4550);
PAINT SKYBLUE (-500 4550);
FORCEPROP 1 LAST VOLTAGE 4V
J 0
(-500 4500);
DISPLAY 0.617021 (-500 4500);
PAINT SKYBLUE (-500 4500);
FORCEPROP 1 LASTPIN (-550 4600) $PN 1
J 0
(-540 4580);
DISPLAY 0.617021 (-540 4580);
PAINT ORANGE (-540 4580);
FORCEPROP 1 LAST TOLERANCE 20%
J 0
(-500 4450);
DISPLAY 0.617021 (-500 4450);
PAINT SKYBLUE (-500 4450);
FORCEPROP 1 LASTPIN (-550 4400) $PN 2
J 0
(-540 4380);
DISPLAY 0.617021 (-540 4380);
PAINT ORANGE (-540 4380);
FORCEPROP 1 LAST MATERIAL X6S
J 0
(-500 4400);
DISPLAY 0.617021 (-500 4400);
PAINT SKYBLUE (-500 4400);
FORCEPROP 2 LAST ROOM PVCCIN_CPU0_DECAP_VR
J 0
(-500 4650);
DISPLAY 1.021277 (-500 4650);
PAINT ORANGE (-500 4650);
DISPLAY INVISIBLE (-500 4650);
FORCEPROP 1 LAST PATH I153
J 0
(-500 4650);
DISPLAY 0.978723 (-500 4650);
PAINT WHITE (-500 4650);
DISPLAY INVISIBLE (-500 4650);
FORCEPROP 2 LAST $SEC 1
J 0
(-500 4700);
PAINT MONO (-500 4700);
DISPLAY INVISIBLE (-500 4700);
FORCEPROP 2 LAST CDS_SEC 1
J 0
(-500 4700);
PAINT MONO (-500 4700);
DISPLAY INVISIBLE (-500 4700);
FORCEPROP 2 LAST CDS_LIB dev_discrete
J 0
(-550 4500);
PAINT ORANGE (-550 4500);
DISPLAY INVISIBLE (-550 4500);
FORCEPROP 2 LAST BOM_COST PROC_SOCKET
J 0
(-500 4700);
DISPLAY 1.021277 (-500 4700);
PAINT ORANGE (-500 4700);
DISPLAY INVISIBLE (-500 4700);
FORCEPROP 2 LAST CDS_LOCATION C5D22
J 0
(-500 4600);
DISPLAY 0.617021 (-500 4600);
PAINT AQUA (-500 4600);
DISPLAY INVISIBLE (-500 4600);
FORCEADD CAP_A..1
(-4450 4500);
FORCEPROP 1 LAST PACK_TYPE 0603V
J 0
(-4400 4350);
DISPLAY 0.617021 (-4400 4350);
PAINT SKYBLUE (-4400 4350);
FORCEPROP 1 LAST PART_NUMBER E15431-004
J 0
(-4400 4400);
DISPLAY 0.617021 (-4400 4400);
PAINT BLUE (-4400 4400);
FORCEPROP 1 LASTPIN (-4450 4600) $PN 1
J 0
(-4440 4580);
DISPLAY 0.617021 (-4440 4580);
PAINT ORANGE (-4440 4580);
FORCEPROP 1 LAST LOCATION C5D26
J 0
(-4400 4650);
DISPLAY 0.617021 (-4400 4650);
PAINT AQUA (-4400 4650);
FORCEPROP 1 LAST VOLTAGE 4V
J 0
(-4400 4550);
DISPLAY 0.617021 (-4400 4550);
PAINT SKYBLUE (-4400 4550);
FORCEPROP 1 LAST TOLERANCE 20%
J 0
(-4400 4500);
DISPLAY 0.617021 (-4400 4500);
PAINT SKYBLUE (-4400 4500);
FORCEPROP 1 LAST MATERIAL X6S
J 0
(-4400 4450);
DISPLAY 0.617021 (-4400 4450);
PAINT SKYBLUE (-4400 4450);
FORCEPROP 1 LASTPIN (-4450 4400) $PN 2
J 0
(-4440 4380);
DISPLAY 0.617021 (-4440 4380);
PAINT ORANGE (-4440 4380);
FORCEPROP 0 LAST GROUP PWR_MLCC_CAP
J 0
(-4395 4252);
DISPLAY 0.638298 (-4395 4252);
PAINT BROWN (-4395 4252);
DISPLAY BOTH (-4395 4252);
FORCEPROP 1 LAST VALUE 22.0UF
J 0
(-4400 4600);
DISPLAY 0.617021 (-4400 4600);
PAINT SKYBLUE (-4400 4600);
FORCEPROP 2 LAST CDS_LOCATION C5D26
J 0
(-4400 4600);
DISPLAY 0.617021 (-4400 4600);
PAINT AQUA (-4400 4600);
DISPLAY INVISIBLE (-4400 4600);
FORCEPROP 2 LAST BOM_COST PROC_SOCKET
J 0
(-4400 4700);
DISPLAY 1.021277 (-4400 4700);
PAINT ORANGE (-4400 4700);
DISPLAY INVISIBLE (-4400 4700);
FORCEPROP 2 LAST CDS_LIB dev_discrete
J 0
(-4450 4500);
PAINT ORANGE (-4450 4500);
DISPLAY INVISIBLE (-4450 4500);
FORCEPROP 2 LAST CDS_SEC 1
J 0
(-4400 4700);
PAINT MONO (-4400 4700);
DISPLAY INVISIBLE (-4400 4700);
FORCEPROP 2 LAST $SEC 1
J 0
(-4400 4700);
PAINT MONO (-4400 4700);
DISPLAY INVISIBLE (-4400 4700);
FORCEPROP 1 LAST PATH I154
J 0
(-4400 4650);
DISPLAY 0.978723 (-4400 4650);
PAINT WHITE (-4400 4650);
DISPLAY INVISIBLE (-4400 4650);
FORCEPROP 2 LAST ROOM PVCCIN_CPU0_DECAP_VR
J 0
(-4400 4650);
DISPLAY 1.021277 (-4400 4650);
PAINT ORANGE (-4400 4650);
DISPLAY INVISIBLE (-4400 4650);
FORCEADD CAP_A..1
(-4600 3800);
FORCEPROP 1 LAST LOCATION C5D25
J 0
(-4550 3950);
DISPLAY 0.617021 (-4550 3950);
PAINT AQUA (-4550 3950);
FORCEPROP 1 LAST PACK_TYPE 0603V
J 0
(-4550 3650);
DISPLAY 0.617021 (-4550 3650);
PAINT SKYBLUE (-4550 3650);
FORCEPROP 1 LAST VALUE 22.0UF
J 0
(-4550 3900);
DISPLAY 0.617021 (-4550 3900);
PAINT SKYBLUE (-4550 3900);
FORCEPROP 1 LAST VOLTAGE 4V
J 0
(-4550 3850);
DISPLAY 0.617021 (-4550 3850);
PAINT SKYBLUE (-4550 3850);
FORCEPROP 1 LAST MATERIAL X6S
J 0
(-4550 3750);
DISPLAY 0.617021 (-4550 3750);
PAINT SKYBLUE (-4550 3750);
FORCEPROP 1 LASTPIN (-4600 3700) $PN 2
J 0
(-4590 3680);
DISPLAY 0.617021 (-4590 3680);
PAINT ORANGE (-4590 3680);
FORCEPROP 1 LASTPIN (-4600 3900) $PN 1
J 0
(-4590 3880);
DISPLAY 0.617021 (-4590 3880);
PAINT ORANGE (-4590 3880);
FORCEPROP 0 LAST GROUP PWR_MLCC_CAP
J 0
(-4545 3602);
DISPLAY 0.638298 (-4545 3602);
PAINT BROWN (-4545 3602);
DISPLAY BOTH (-4545 3602);
FORCEPROP 1 LAST PART_NUMBER E15431-004
J 0
(-4550 3700);
DISPLAY 0.617021 (-4550 3700);
PAINT BLUE (-4550 3700);
FORCEPROP 1 LAST TOLERANCE 20%
J 0
(-4550 3800);
DISPLAY 0.617021 (-4550 3800);
PAINT SKYBLUE (-4550 3800);
FORCEPROP 2 LAST ROOM PVCCIN_CPU0_DECAP_VR
J 0
(-4550 3950);
DISPLAY 1.021277 (-4550 3950);
PAINT ORANGE (-4550 3950);
DISPLAY INVISIBLE (-4550 3950);
FORCEPROP 1 LAST PATH I155
J 0
(-4550 3950);
DISPLAY 0.978723 (-4550 3950);
PAINT WHITE (-4550 3950);
DISPLAY INVISIBLE (-4550 3950);
FORCEPROP 2 LAST $SEC 1
J 0
(-4550 4000);
PAINT MONO (-4550 4000);
DISPLAY INVISIBLE (-4550 4000);
FORCEPROP 2 LAST CDS_SEC 1
J 0
(-4550 4000);
PAINT MONO (-4550 4000);
DISPLAY INVISIBLE (-4550 4000);
FORCEPROP 2 LAST CDS_LIB dev_discrete
J 0
(-4600 3800);
PAINT ORANGE (-4600 3800);
DISPLAY INVISIBLE (-4600 3800);
FORCEPROP 2 LAST BOM_COST PROC_SOCKET
J 0
(-4550 4000);
DISPLAY 1.021277 (-4550 4000);
PAINT ORANGE (-4550 4000);
DISPLAY INVISIBLE (-4550 4000);
FORCEPROP 2 LAST CDS_LOCATION C5D25
J 0
(-4550 3900);
DISPLAY 0.617021 (-4550 3900);
PAINT AQUA (-4550 3900);
DISPLAY INVISIBLE (-4550 3900);
FORCEADD CAP_A..1
(-4700 3150);
FORCEPROP 1 LAST MATERIAL X6S
J 0
(-4650 3100);
DISPLAY 0.617021 (-4650 3100);
PAINT SKYBLUE (-4650 3100);
FORCEPROP 1 LASTPIN (-4700 3250) $PN 1
J 0
(-4690 3230);
DISPLAY 0.617021 (-4690 3230);
PAINT ORANGE (-4690 3230);
FORCEPROP 1 LAST VOLTAGE 4V
J 0
(-4650 3200);
DISPLAY 0.617021 (-4650 3200);
PAINT SKYBLUE (-4650 3200);
FORCEPROP 1 LAST VALUE 22.0UF
J 0
(-4650 3250);
DISPLAY 0.617021 (-4650 3250);
PAINT SKYBLUE (-4650 3250);
FORCEPROP 1 LAST LOCATION C5D45
J 0
(-4650 3300);
DISPLAY 0.617021 (-4650 3300);
PAINT AQUA (-4650 3300);
FORCEPROP 1 LASTPIN (-4700 3050) $PN 2
J 0
(-4690 3030);
DISPLAY 0.617021 (-4690 3030);
PAINT ORANGE (-4690 3030);
FORCEPROP 1 LAST PACK_TYPE 0603V
J 0
(-4650 3000);
DISPLAY 0.617021 (-4650 3000);
PAINT SKYBLUE (-4650 3000);
FORCEPROP 1 LAST PART_NUMBER E15431-004
J 0
(-4650 3050);
DISPLAY 0.617021 (-4650 3050);
PAINT BLUE (-4650 3050);
FORCEPROP 1 LAST TOLERANCE 20%
J 0
(-4650 3150);
DISPLAY 0.617021 (-4650 3150);
PAINT SKYBLUE (-4650 3150);
FORCEPROP 0 LAST GROUP PWR_MLCC_CAP
J 0
(-4645 2952);
DISPLAY 0.638298 (-4645 2952);
PAINT BROWN (-4645 2952);
DISPLAY BOTH (-4645 2952);
FORCEPROP 2 LAST ROOM PVCCIN_CPU0_DECAP_VR
J 0
(-4650 3300);
DISPLAY 1.021277 (-4650 3300);
PAINT ORANGE (-4650 3300);
DISPLAY INVISIBLE (-4650 3300);
FORCEPROP 1 LAST PATH I156
J 0
(-4650 3300);
DISPLAY 0.978723 (-4650 3300);
PAINT WHITE (-4650 3300);
DISPLAY INVISIBLE (-4650 3300);
FORCEPROP 2 LAST $SEC 1
J 0
(-4650 3350);
PAINT MONO (-4650 3350);
DISPLAY INVISIBLE (-4650 3350);
FORCEPROP 2 LAST CDS_SEC 1
J 0
(-4650 3350);
PAINT MONO (-4650 3350);
DISPLAY INVISIBLE (-4650 3350);
FORCEPROP 2 LAST CDS_LIB dev_discrete
J 0
(-4700 3150);
PAINT ORANGE (-4700 3150);
DISPLAY INVISIBLE (-4700 3150);
FORCEPROP 2 LAST BOM_COST PROC_SOCKET
J 0
(-4650 3350);
DISPLAY 1.021277 (-4650 3350);
PAINT ORANGE (-4650 3350);
DISPLAY INVISIBLE (-4650 3350);
FORCEPROP 2 LAST CDS_LOCATION C5D45
J 0
(-4650 3250);
DISPLAY 0.617021 (-4650 3250);
PAINT AQUA (-4650 3250);
DISPLAY INVISIBLE (-4650 3250);
FORCEADD VCC_CORE..1
(-4750 2525);
FORCEPROP 3 LASTPIN (-4750 2475) SIG_NAME PVCCMCP_CPU0\g
J 0
(-4740 2485);
DISPLAY 0.659574 (-4740 2485);
PAINT MONO (-4740 2485);
DISPLAY INVISIBLE (-4740 2485);
FORCEPROP 1 LAST HDL_POWER PVCCMCP_CPU0
J 1
(-4750 2575);
DISPLAY 0.617021 (-4750 2575);
PAINT GREEN (-4750 2575);
FORCEPROP 1 LAST PATH I159
J 0
(-4700 2550);
DISPLAY 0.872340 (-4700 2550);
PAINT AQUA (-4700 2550);
DISPLAY INVISIBLE (-4700 2550);
FORCEPROP 2 LAST CDS_LIB mstr_symbols
J 0
(-4750 2525);
PAINT ORANGE (-4750 2525);
DISPLAY INVISIBLE (-4750 2525);
FORCEADD PVCCIO_CPU0..1
(-3200 1275);
FORCEPROP 3 LASTPIN (-3200 1225) SIG_NAME PVCCIO_CPU0\g
J 0
(-3190 1235);
DISPLAY 0.659574 (-3190 1235);
PAINT MONO (-3190 1235);
DISPLAY INVISIBLE (-3190 1235);
FORCEPROP 1 LAST HDL_POWER PVCCIO_CPU0
J 1
(-3200 1325);
DISPLAY 0.872340 (-3200 1325);
PAINT GREEN (-3200 1325);
DISPLAY INVISIBLE (-3200 1325);
FORCEPROP 1 LAST PATH I16
J 0
(-3150 1300);
DISPLAY 0.872340 (-3150 1300);
PAINT AQUA (-3150 1300);
DISPLAY INVISIBLE (-3150 1300);
FORCEPROP 1 LAST BODY_TYPE PLUMBING
J 0
(-3245 1232);
DISPLAY 0.340426 (-3245 1232);
PAINT GREEN (-3245 1232);
DISPLAY INVISIBLE (-3245 1232);
FORCEPROP 2 LAST CDS_LIB mstr_symbols
J 0
(-3200 1275);
PAINT ORANGE (-3200 1275);
DISPLAY INVISIBLE (-3200 1275);
FORCEPROP 1 LAST VOLTAGE 1.1V
J 0
(-3245 1232);
DISPLAY 0.340426 (-3245 1232);
PAINT SKYBLUE (-3245 1232);
DISPLAY INVISIBLE (-3245 1232);
FORCEADD CAP_A..1
(-2250 950);
FORCEPROP 1 LASTPIN (-2250 1050) $PN 1
J 0
(-2240 1030);
DISPLAY 0.617021 (-2240 1030);
PAINT ORANGE (-2240 1030);
FORCEPROP 1 LAST VALUE 22.0UF
J 0
(-2200 1050);
DISPLAY 0.617021 (-2200 1050);
PAINT SKYBLUE (-2200 1050);
FORCEPROP 1 LASTPIN (-2250 850) $PN 2
J 0
(-2240 830);
DISPLAY 0.617021 (-2240 830);
PAINT ORANGE (-2240 830);
FORCEPROP 1 LAST TOLERANCE 20%
J 0
(-2200 950);
DISPLAY 0.617021 (-2200 950);
PAINT SKYBLUE (-2200 950);
FORCEPROP 1 LAST VOLTAGE 4V
J 0
(-2200 1000);
DISPLAY 0.617021 (-2200 1000);
PAINT SKYBLUE (-2200 1000);
FORCEPROP 1 LAST PACK_TYPE 0603V
J 0
(-2200 800);
DISPLAY 0.617021 (-2200 800);
PAINT SKYBLUE (-2200 800);
FORCEPROP 1 LAST PART_NUMBER E15431-004
J 0
(-2200 850);
DISPLAY 0.617021 (-2200 850);
PAINT BLUE (-2200 850);
FORCEPROP 1 LAST MATERIAL X6S
J 0
(-2200 900);
DISPLAY 0.617021 (-2200 900);
PAINT SKYBLUE (-2200 900);
FORCEPROP 0 LAST GROUP PWR_MLCC_CAP
J 0
(-2194 712);
DISPLAY 0.638298 (-2194 712);
PAINT BROWN (-2194 712);
DISPLAY BOTH (-2194 712);
FORCEPROP 1 LAST LOCATION C4P6
J 0
(-2200 1100);
DISPLAY 0.617021 (-2200 1100);
PAINT AQUA (-2200 1100);
FORCEPROP 2 LAST CDS_LOCATION C4P6
J 0
(-2200 1050);
DISPLAY 0.617021 (-2200 1050);
PAINT AQUA (-2200 1050);
DISPLAY INVISIBLE (-2200 1050);
FORCEPROP 2 LAST CDS_LIB dev_discrete
J 0
(-2250 950);
PAINT ORANGE (-2250 950);
DISPLAY INVISIBLE (-2250 950);
FORCEPROP 2 LAST CDS_SEC 1
J 0
(-2200 1150);
PAINT MONO (-2200 1150);
DISPLAY INVISIBLE (-2200 1150);
FORCEPROP 2 LAST $SEC 1
J 0
(-2200 1150);
PAINT MONO (-2200 1150);
DISPLAY INVISIBLE (-2200 1150);
FORCEPROP 1 LAST PATH I164
J 0
(-2200 1100);
DISPLAY 0.978723 (-2200 1100);
PAINT WHITE (-2200 1100);
DISPLAY INVISIBLE (-2200 1100);
FORCEPROP 0 LAST ROOM PVCCIN_CPU0_DECAP_VR
J 0
(-2200 1150);
DISPLAY 1.021277 (-2200 1150);
PAINT ORANGE (-2200 1150);
DISPLAY INVISIBLE (-2200 1150);
FORCEADD CAP..1
(-3200 950);
FORCEPROP 1 LAST VOLTAGE 4V
J 0
(-3150 1000);
DISPLAY 0.638298 (-3150 1000);
PAINT SKYBLUE (-3150 1000);
FORCEPROP 1 LAST VALUE 47UF
J 0
(-3150 1050);
DISPLAY 0.617021 (-3150 1050);
PAINT SKYBLUE (-3150 1050);
FORCEPROP 1 LASTPIN (-3200 1050) $PN 1
J 0
(-3190 1030);
DISPLAY 0.617021 (-3190 1030);
PAINT ORANGE (-3190 1030);
FORCEPROP 1 LAST LOCATION C4P10
J 0
(-3150 1100);
DISPLAY 0.617021 (-3150 1100);
PAINT AQUA (-3150 1100);
FORCEPROP 1 LAST TOLERANCE 20%
J 0
(-3150 950);
DISPLAY 0.617021 (-3150 950);
PAINT SKYBLUE (-3150 950);
FORCEPROP 1 LAST MATERIAL X6S
J 0
(-3150 900);
DISPLAY 0.617021 (-3150 900);
PAINT SKYBLUE (-3150 900);
FORCEPROP 1 LASTPIN (-3200 850) $PN 2
J 0
(-3190 830);
DISPLAY 0.617021 (-3190 830);
PAINT ORANGE (-3190 830);
FORCEPROP 1 LAST PACK_TYPE 0805
J 0
(-3150 800);
DISPLAY 0.617021 (-3150 800);
PAINT SKYBLUE (-3150 800);
FORCEPROP 1 LAST PART_NUMBER C95333-006
J 0
(-3150 850);
DISPLAY 0.617021 (-3150 850);
PAINT BLUE (-3150 850);
FORCEPROP 0 LAST GROUP PWR_MLCC_CAP
J 0
(-3144 762);
DISPLAY 0.638298 (-3144 762);
PAINT BROWN (-3144 762);
DISPLAY BOTH (-3144 762);
FORCEPROP 2 LAST ROOM PVCCIN_CPU0_DECAP_VR
J 0
(-3150 1100);
DISPLAY 1.021277 (-3150 1100);
PAINT ORANGE (-3150 1100);
DISPLAY INVISIBLE (-3150 1100);
FORCEPROP 1 LAST PATH I17
J 0
(-3150 1100);
DISPLAY 0.978723 (-3150 1100);
PAINT WHITE (-3150 1100);
DISPLAY INVISIBLE (-3150 1100);
FORCEPROP 2 LAST CDS_LOCATION C4P10
J 0
(-3150 1050);
DISPLAY 0.617021 (-3150 1050);
PAINT AQUA (-3150 1050);
DISPLAY INVISIBLE (-3150 1050);
FORCEPROP 2 LAST $SEC 1
J 0
(-3140 1170);
PAINT MONO (-3140 1170);
DISPLAY INVISIBLE (-3140 1170);
FORCEPROP 2 LAST CDS_SEC 1
J 0
(-3140 1170);
PAINT MONO (-3140 1170);
DISPLAY INVISIBLE (-3140 1170);
FORCEPROP 2 LAST CDS_LIB mstr_discrete
J 0
(-3200 950);
PAINT ORANGE (-3200 950);
DISPLAY INVISIBLE (-3200 950);
FORCEPROP 2 LAST BOM_COST PROC_SOCKET
J 0
(-3150 1150);
DISPLAY 1.021277 (-3150 1150);
PAINT ORANGE (-3150 1150);
DISPLAY INVISIBLE (-3150 1150);
FORCEADD CAP_A..1
(-1050 3850);
FORCEPROP 1 LAST TOLERANCE 20%
J 0
(-1000 3800);
DISPLAY 0.617021 (-1000 3800);
PAINT SKYBLUE (-1000 3800);
FORCEPROP 1 LAST PART_NUMBER E15431-004
J 0
(-1000 3700);
DISPLAY 0.617021 (-1000 3700);
PAINT BLUE (-1000 3700);
FORCEPROP 1 LAST PACK_TYPE 0603V
J 0
(-1000 3650);
DISPLAY 0.617021 (-1000 3650);
PAINT SKYBLUE (-1000 3650);
FORCEPROP 1 LAST LOCATION C5D20
J 0
(-1000 3950);
DISPLAY 0.617021 (-1000 3950);
PAINT AQUA (-1000 3950);
FORCEPROP 1 LAST MATERIAL X6S
J 0
(-1000 3750);
DISPLAY 0.617021 (-1000 3750);
PAINT SKYBLUE (-1000 3750);
FORCEPROP 1 LAST VOLTAGE 4V
J 0
(-1000 3850);
DISPLAY 0.617021 (-1000 3850);
PAINT SKYBLUE (-1000 3850);
FORCEPROP 1 LAST VALUE 22.0UF
J 0
(-1000 3900);
DISPLAY 0.617021 (-1000 3900);
PAINT SKYBLUE (-1000 3900);
FORCEPROP 0 LAST GROUP PWR_MCP_CAP
J 0
(-1000 3550);
DISPLAY 0.638298 (-1000 3550);
PAINT BROWN (-1000 3550);
DISPLAY BOTH (-1000 3550);
FORCEPROP 1 LASTPIN (-1050 3750) $PN 2
J 0
(-1040 3730);
DISPLAY 0.787234 (-1040 3730);
PAINT ORANGE (-1040 3730);
DISPLAY INVISIBLE (-1040 3730);
FORCEPROP 1 LASTPIN (-1050 3950) $PN 1
J 0
(-1040 3930);
DISPLAY 0.787234 (-1040 3930);
PAINT ORANGE (-1040 3930);
DISPLAY INVISIBLE (-1040 3930);
FORCEPROP 2 LAST ROOM PVCCIN_CPU0_DECAP_VR
J 0
(-1000 4000);
DISPLAY 1.021277 (-1000 4000);
PAINT ORANGE (-1000 4000);
DISPLAY INVISIBLE (-1000 4000);
FORCEPROP 1 LAST PATH I173
J 0
(-1000 4000);
DISPLAY 0.978723 (-1000 4000);
PAINT WHITE (-1000 4000);
DISPLAY INVISIBLE (-1000 4000);
FORCEPROP 2 LAST $SEC 1
J 0
(-1000 4050);
PAINT MONO (-1000 4050);
DISPLAY INVISIBLE (-1000 4050);
FORCEPROP 2 LAST CDS_SEC 1
J 0
(-1000 4050);
PAINT MONO (-1000 4050);
DISPLAY INVISIBLE (-1000 4050);
FORCEPROP 2 LAST CDS_LIB dev_discrete
J 0
(-1050 3850);
PAINT ORANGE (-1050 3850);
DISPLAY INVISIBLE (-1050 3850);
FORCEPROP 2 LAST BOM_COST PROC_SOCKET
J 0
(-1000 4050);
DISPLAY 1.021277 (-1000 4050);
PAINT ORANGE (-1000 4050);
DISPLAY INVISIBLE (-1000 4050);
FORCEPROP 2 LAST CDS_LOCATION C5D20
J 0
(-1000 3950);
DISPLAY 0.617021 (-1000 3950);
PAINT AQUA (-1000 3950);
DISPLAY INVISIBLE (-1000 3950);
FORCEADD CAP_A..1
(-800 3850);
FORCEPROP 1 LAST LOCATION C5D33
J 0
(-750 3950);
DISPLAY 0.617021 (-750 3950);
PAINT AQUA (-750 3950);
FORCEPROP 1 LAST VALUE 22.0UF
J 0
(-750 3900);
DISPLAY 0.617021 (-750 3900);
PAINT SKYBLUE (-750 3900);
FORCEPROP 1 LAST TOLERANCE 20%
J 0
(-750 3800);
DISPLAY 0.617021 (-750 3800);
PAINT SKYBLUE (-750 3800);
FORCEPROP 1 LAST MATERIAL X6S
J 0
(-750 3750);
DISPLAY 0.617021 (-750 3750);
PAINT SKYBLUE (-750 3750);
FORCEPROP 1 LAST PACK_TYPE 0603V
J 0
(-750 3650);
DISPLAY 0.617021 (-750 3650);
PAINT SKYBLUE (-750 3650);
FORCEPROP 1 LAST PART_NUMBER E15431-004
J 0
(-750 3700);
DISPLAY 0.617021 (-750 3700);
PAINT BLUE (-750 3700);
FORCEPROP 1 LAST VOLTAGE 4V
J 0
(-750 3850);
DISPLAY 0.617021 (-750 3850);
PAINT SKYBLUE (-750 3850);
FORCEPROP 0 LAST GROUP PWR_MCP_CAP
J 0
(-750 3600);
DISPLAY 0.638298 (-750 3600);
PAINT BROWN (-750 3600);
DISPLAY BOTH (-750 3600);
FORCEPROP 2 LAST CDS_LOCATION C5D33
J 0
(-750 3950);
DISPLAY 0.617021 (-750 3950);
PAINT AQUA (-750 3950);
DISPLAY INVISIBLE (-750 3950);
FORCEPROP 2 LAST BOM_COST PROC_SOCKET
J 0
(-750 4050);
DISPLAY 1.021277 (-750 4050);
PAINT ORANGE (-750 4050);
DISPLAY INVISIBLE (-750 4050);
FORCEPROP 2 LAST CDS_LIB dev_discrete
J 0
(-800 3850);
PAINT ORANGE (-800 3850);
DISPLAY INVISIBLE (-800 3850);
FORCEPROP 2 LAST CDS_SEC 1
J 0
(-750 4050);
PAINT MONO (-750 4050);
DISPLAY INVISIBLE (-750 4050);
FORCEPROP 2 LAST $SEC 1
J 0
(-750 4050);
PAINT MONO (-750 4050);
DISPLAY INVISIBLE (-750 4050);
FORCEPROP 2 LAST ROOM PVCCIN_CPU0_DECAP_VR
J 0
(-750 4000);
DISPLAY 1.021277 (-750 4000);
PAINT ORANGE (-750 4000);
DISPLAY INVISIBLE (-750 4000);
FORCEPROP 1 LASTPIN (-800 3950) $PN 1
J 0
(-790 3930);
DISPLAY 0.787234 (-790 3930);
PAINT ORANGE (-790 3930);
DISPLAY INVISIBLE (-790 3930);
FORCEPROP 1 LASTPIN (-800 3750) $PN 2
J 0
(-790 3730);
DISPLAY 0.787234 (-790 3730);
PAINT ORANGE (-790 3730);
DISPLAY INVISIBLE (-790 3730);
FORCEPROP 1 LAST PATH I174
J 0
(-750 4000);
DISPLAY 0.978723 (-750 4000);
PAINT WHITE (-750 4000);
DISPLAY INVISIBLE (-750 4000);
FORCEADD CAP_A..1
(-550 3850);
FORCEPROP 1 LAST LOCATION C5D34
J 0
(-500 3950);
DISPLAY 0.617021 (-500 3950);
PAINT AQUA (-500 3950);
FORCEPROP 1 LAST VALUE 22.0UF
J 0
(-500 3900);
DISPLAY 0.617021 (-500 3900);
PAINT SKYBLUE (-500 3900);
FORCEPROP 1 LAST PACK_TYPE 0603V
J 0
(-500 3650);
DISPLAY 0.617021 (-500 3650);
PAINT SKYBLUE (-500 3650);
FORCEPROP 1 LAST VOLTAGE 4V
J 0
(-500 3850);
DISPLAY 0.617021 (-500 3850);
PAINT SKYBLUE (-500 3850);
FORCEPROP 1 LAST TOLERANCE 20%
J 0
(-500 3800);
DISPLAY 0.617021 (-500 3800);
PAINT SKYBLUE (-500 3800);
FORCEPROP 1 LAST MATERIAL X6S
J 0
(-500 3750);
DISPLAY 0.617021 (-500 3750);
PAINT SKYBLUE (-500 3750);
FORCEPROP 1 LAST PART_NUMBER E15431-004
J 0
(-500 3700);
DISPLAY 0.617021 (-500 3700);
PAINT BLUE (-500 3700);
FORCEPROP 0 LAST GROUP PWR_MCP_CAP
J 0
(-500 3550);
DISPLAY 0.638298 (-500 3550);
PAINT BROWN (-500 3550);
DISPLAY BOTH (-500 3550);
FORCEPROP 2 LAST CDS_LOCATION C5D34
J 0
(-500 3950);
DISPLAY 0.617021 (-500 3950);
PAINT AQUA (-500 3950);
DISPLAY INVISIBLE (-500 3950);
FORCEPROP 2 LAST BOM_COST PROC_SOCKET
J 0
(-500 4050);
DISPLAY 1.021277 (-500 4050);
PAINT ORANGE (-500 4050);
DISPLAY INVISIBLE (-500 4050);
FORCEPROP 2 LAST CDS_LIB dev_discrete
J 0
(-550 3850);
PAINT ORANGE (-550 3850);
DISPLAY INVISIBLE (-550 3850);
FORCEPROP 2 LAST CDS_SEC 1
J 0
(-500 4050);
PAINT MONO (-500 4050);
DISPLAY INVISIBLE (-500 4050);
FORCEPROP 2 LAST $SEC 1
J 0
(-500 4050);
PAINT MONO (-500 4050);
DISPLAY INVISIBLE (-500 4050);
FORCEPROP 1 LAST PATH I175
J 0
(-500 4000);
DISPLAY 0.978723 (-500 4000);
PAINT WHITE (-500 4000);
DISPLAY INVISIBLE (-500 4000);
FORCEPROP 2 LAST ROOM PVCCIN_CPU0_DECAP_VR
J 0
(-500 4000);
DISPLAY 1.021277 (-500 4000);
PAINT ORANGE (-500 4000);
DISPLAY INVISIBLE (-500 4000);
FORCEPROP 1 LASTPIN (-550 3950) $PN 1
J 0
(-540 3930);
DISPLAY 0.787234 (-540 3930);
PAINT ORANGE (-540 3930);
DISPLAY INVISIBLE (-540 3930);
FORCEPROP 1 LASTPIN (-550 3750) $PN 2
J 0
(-540 3730);
DISPLAY 0.787234 (-540 3730);
PAINT ORANGE (-540 3730);
DISPLAY INVISIBLE (-540 3730);
FORCEADD CAP_A..1
(-1300 3850);
FORCEPROP 1 LAST MATERIAL X6S
J 0
(-1250 3750);
DISPLAY 0.617021 (-1250 3750);
PAINT SKYBLUE (-1250 3750);
FORCEPROP 1 LAST PART_NUMBER E15431-004
J 0
(-1250 3700);
DISPLAY 0.617021 (-1250 3700);
PAINT BLUE (-1250 3700);
FORCEPROP 0 LAST GROUP PWR_MCP_CAP
J 0
(-1250 3600);
DISPLAY 0.638298 (-1250 3600);
PAINT BROWN (-1250 3600);
DISPLAY BOTH (-1250 3600);
FORCEPROP 1 LAST TOLERANCE 20%
J 0
(-1250 3800);
DISPLAY 0.617021 (-1250 3800);
PAINT SKYBLUE (-1250 3800);
FORCEPROP 1 LAST VOLTAGE 4V
J 0
(-1250 3850);
DISPLAY 0.617021 (-1250 3850);
PAINT SKYBLUE (-1250 3850);
FORCEPROP 1 LAST LOCATION C5D35
J 0
(-1250 3950);
DISPLAY 0.617021 (-1250 3950);
PAINT AQUA (-1250 3950);
FORCEPROP 1 LAST VALUE 22.0UF
J 0
(-1250 3900);
DISPLAY 0.617021 (-1250 3900);
PAINT SKYBLUE (-1250 3900);
FORCEPROP 1 LAST PACK_TYPE 0603V
J 0
(-1250 3650);
DISPLAY 0.617021 (-1250 3650);
PAINT SKYBLUE (-1250 3650);
FORCEPROP 1 LASTPIN (-1300 3750) $PN 2
J 0
(-1290 3730);
DISPLAY 0.787234 (-1290 3730);
PAINT ORANGE (-1290 3730);
DISPLAY INVISIBLE (-1290 3730);
FORCEPROP 1 LASTPIN (-1300 3950) $PN 1
J 0
(-1290 3930);
DISPLAY 0.787234 (-1290 3930);
PAINT ORANGE (-1290 3930);
DISPLAY INVISIBLE (-1290 3930);
FORCEPROP 2 LAST ROOM PVCCIN_CPU0_DECAP_VR
J 0
(-1250 4000);
DISPLAY 1.021277 (-1250 4000);
PAINT ORANGE (-1250 4000);
DISPLAY INVISIBLE (-1250 4000);
FORCEPROP 1 LAST PATH I176
J 0
(-1250 4000);
DISPLAY 0.978723 (-1250 4000);
PAINT WHITE (-1250 4000);
DISPLAY INVISIBLE (-1250 4000);
FORCEPROP 2 LAST $SEC 1
J 0
(-1250 4050);
PAINT MONO (-1250 4050);
DISPLAY INVISIBLE (-1250 4050);
FORCEPROP 2 LAST CDS_SEC 1
J 0
(-1250 4050);
PAINT MONO (-1250 4050);
DISPLAY INVISIBLE (-1250 4050);
FORCEPROP 2 LAST CDS_LIB dev_discrete
J 0
(-1300 3850);
PAINT ORANGE (-1300 3850);
DISPLAY INVISIBLE (-1300 3850);
FORCEPROP 2 LAST BOM_COST PROC_SOCKET
J 0
(-1250 4050);
DISPLAY 1.021277 (-1250 4050);
PAINT ORANGE (-1250 4050);
DISPLAY INVISIBLE (-1250 4050);
FORCEPROP 2 LAST CDS_LOCATION C5D35
J 0
(-1250 3950);
DISPLAY 0.617021 (-1250 3950);
PAINT AQUA (-1250 3950);
DISPLAY INVISIBLE (-1250 3950);
FORCEADD CAP_A..1
(-1950 950);
FORCEPROP 1 LAST VALUE 22.0UF
J 0
(-1900 1050);
DISPLAY 0.617021 (-1900 1050);
PAINT SKYBLUE (-1900 1050);
FORCEPROP 1 LAST VOLTAGE 4V
J 0
(-1900 1000);
DISPLAY 0.617021 (-1900 1000);
PAINT SKYBLUE (-1900 1000);
FORCEPROP 1 LAST TOLERANCE 20%
J 0
(-1900 950);
DISPLAY 0.617021 (-1900 950);
PAINT SKYBLUE (-1900 950);
FORCEPROP 1 LAST MATERIAL X6S
J 0
(-1900 900);
DISPLAY 0.617021 (-1900 900);
PAINT SKYBLUE (-1900 900);
FORCEPROP 1 LAST PART_NUMBER E15431-004
J 0
(-1900 850);
DISPLAY 0.617021 (-1900 850);
PAINT BLUE (-1900 850);
FORCEPROP 1 LAST PACK_TYPE 0603V
J 0
(-1900 800);
DISPLAY 0.617021 (-1900 800);
PAINT SKYBLUE (-1900 800);
FORCEPROP 1 LAST LOCATION C4P8
J 0
(-1900 1100);
DISPLAY 0.617021 (-1900 1100);
PAINT AQUA (-1900 1100);
FORCEPROP 0 LAST GROUP PWR_MLCC_CAP
J 0
(-1894 762);
DISPLAY 0.638298 (-1894 762);
PAINT BROWN (-1894 762);
DISPLAY BOTH (-1894 762);
FORCEPROP 2 LAST CDS_LOCATION C4P8
J 0
(-1900 1050);
DISPLAY 0.617021 (-1900 1050);
PAINT AQUA (-1900 1050);
DISPLAY INVISIBLE (-1900 1050);
FORCEPROP 2 LAST CDS_LIB dev_discrete
J 0
(-1950 950);
PAINT ORANGE (-1950 950);
DISPLAY INVISIBLE (-1950 950);
FORCEPROP 2 LAST CDS_SEC 1
J 0
(-1900 1150);
PAINT MONO (-1900 1150);
DISPLAY INVISIBLE (-1900 1150);
FORCEPROP 2 LAST $SEC 1
J 0
(-1900 1150);
PAINT MONO (-1900 1150);
DISPLAY INVISIBLE (-1900 1150);
FORCEPROP 1 LAST PATH I178
J 0
(-1900 1100);
DISPLAY 0.978723 (-1900 1100);
PAINT WHITE (-1900 1100);
DISPLAY INVISIBLE (-1900 1100);
FORCEPROP 0 LAST ROOM PVCCIN_CPU0_DECAP_VR
J 0
(-1900 1100);
DISPLAY 1.021277 (-1900 1100);
PAINT ORANGE (-1900 1100);
DISPLAY INVISIBLE (-1900 1100);
FORCEPROP 1 LASTPIN (-1950 1050) $PN 1
J 0
(-1940 1030);
DISPLAY 0.787234 (-1940 1030);
PAINT ORANGE (-1940 1030);
DISPLAY INVISIBLE (-1940 1030);
FORCEPROP 1 LASTPIN (-1950 850) $PN 2
J 0
(-1940 830);
DISPLAY 0.787234 (-1940 830);
PAINT ORANGE (-1940 830);
DISPLAY INVISIBLE (-1940 830);
FORCEADD CAP_A..1
(-1550 3850);
FORCEPROP 1 LAST LOCATION C5D53
J 0
(-1500 3950);
DISPLAY 0.617021 (-1500 3950);
PAINT AQUA (-1500 3950);
FORCEPROP 1 LAST VOLTAGE 4V
J 0
(-1500 3850);
DISPLAY 0.617021 (-1500 3850);
PAINT SKYBLUE (-1500 3850);
FORCEPROP 1 LAST VALUE 22.0UF
J 0
(-1500 3900);
DISPLAY 0.617021 (-1500 3900);
PAINT SKYBLUE (-1500 3900);
FORCEPROP 0 LAST GROUP PWR_MCP_CAP
J 0
(-1500 3550);
DISPLAY 0.638298 (-1500 3550);
PAINT BROWN (-1500 3550);
DISPLAY BOTH (-1500 3550);
FORCEPROP 1 LAST PACK_TYPE 0603V
J 0
(-1500 3650);
DISPLAY 0.617021 (-1500 3650);
PAINT SKYBLUE (-1500 3650);
FORCEPROP 1 LAST PART_NUMBER E15431-004
J 0
(-1500 3700);
DISPLAY 0.617021 (-1500 3700);
PAINT BLUE (-1500 3700);
FORCEPROP 1 LAST MATERIAL X6S
J 0
(-1500 3750);
DISPLAY 0.617021 (-1500 3750);
PAINT SKYBLUE (-1500 3750);
FORCEPROP 1 LAST TOLERANCE 20%
J 0
(-1500 3800);
DISPLAY 0.617021 (-1500 3800);
PAINT SKYBLUE (-1500 3800);
FORCEPROP 1 LASTPIN (-1550 3750) $PN 2
J 0
(-1540 3730);
DISPLAY 0.787234 (-1540 3730);
PAINT ORANGE (-1540 3730);
DISPLAY INVISIBLE (-1540 3730);
FORCEPROP 1 LASTPIN (-1550 3950) $PN 1
J 0
(-1540 3930);
DISPLAY 0.787234 (-1540 3930);
PAINT ORANGE (-1540 3930);
DISPLAY INVISIBLE (-1540 3930);
FORCEPROP 0 LAST ROOM PVCCIN_CPU0_DECAP_VR
J 0
(-1500 4000);
DISPLAY 1.021277 (-1500 4000);
PAINT ORANGE (-1500 4000);
DISPLAY INVISIBLE (-1500 4000);
FORCEPROP 1 LAST PATH I179
J 0
(-1500 4000);
DISPLAY 0.978723 (-1500 4000);
PAINT WHITE (-1500 4000);
DISPLAY INVISIBLE (-1500 4000);
FORCEPROP 2 LAST $SEC 1
J 0
(-1500 4050);
PAINT MONO (-1500 4050);
DISPLAY INVISIBLE (-1500 4050);
FORCEPROP 2 LAST CDS_SEC 1
J 0
(-1500 4050);
PAINT MONO (-1500 4050);
DISPLAY INVISIBLE (-1500 4050);
FORCEPROP 2 LAST CDS_LIB dev_discrete
J 0
(-1550 3850);
PAINT ORANGE (-1550 3850);
DISPLAY INVISIBLE (-1550 3850);
FORCEPROP 2 LAST CDS_LOCATION C5D53
J 0
(-1500 3950);
DISPLAY 0.617021 (-1500 3950);
PAINT AQUA (-1500 3950);
DISPLAY INVISIBLE (-1500 3950);
FORCEADD CAP_A..1
(-1800 3850);
FORCEPROP 0 LAST GROUP PWR_MCP_CAP
J 0
(-1750 3600);
DISPLAY 0.638298 (-1750 3600);
PAINT BROWN (-1750 3600);
DISPLAY BOTH (-1750 3600);
FORCEPROP 1 LAST MATERIAL X6S
J 0
(-1750 3750);
DISPLAY 0.617021 (-1750 3750);
PAINT SKYBLUE (-1750 3750);
FORCEPROP 1 LAST PART_NUMBER E15431-004
J 0
(-1750 3700);
DISPLAY 0.617021 (-1750 3700);
PAINT BLUE (-1750 3700);
FORCEPROP 1 LAST VALUE 22.0UF
J 0
(-1750 3900);
DISPLAY 0.617021 (-1750 3900);
PAINT SKYBLUE (-1750 3900);
FORCEPROP 1 LAST LOCATION C5D52
J 0
(-1750 3950);
DISPLAY 0.617021 (-1750 3950);
PAINT AQUA (-1750 3950);
FORCEPROP 1 LAST PACK_TYPE 0603V
J 0
(-1750 3650);
DISPLAY 0.617021 (-1750 3650);
PAINT SKYBLUE (-1750 3650);
FORCEPROP 1 LAST TOLERANCE 20%
J 0
(-1750 3800);
DISPLAY 0.617021 (-1750 3800);
PAINT SKYBLUE (-1750 3800);
FORCEPROP 1 LAST VOLTAGE 4V
J 0
(-1750 3850);
DISPLAY 0.617021 (-1750 3850);
PAINT SKYBLUE (-1750 3850);
FORCEPROP 1 LASTPIN (-1800 3750) $PN 2
J 0
(-1790 3730);
DISPLAY 0.787234 (-1790 3730);
PAINT ORANGE (-1790 3730);
DISPLAY INVISIBLE (-1790 3730);
FORCEPROP 1 LASTPIN (-1800 3950) $PN 1
J 0
(-1790 3930);
DISPLAY 0.787234 (-1790 3930);
PAINT ORANGE (-1790 3930);
DISPLAY INVISIBLE (-1790 3930);
FORCEPROP 0 LAST ROOM PVCCIN_CPU0_DECAP_VR
J 0
(-1750 4000);
DISPLAY 1.021277 (-1750 4000);
PAINT ORANGE (-1750 4000);
DISPLAY INVISIBLE (-1750 4000);
FORCEPROP 1 LAST PATH I180
J 0
(-1750 4000);
DISPLAY 0.978723 (-1750 4000);
PAINT WHITE (-1750 4000);
DISPLAY INVISIBLE (-1750 4000);
FORCEPROP 2 LAST $SEC 1
J 0
(-1750 4050);
PAINT MONO (-1750 4050);
DISPLAY INVISIBLE (-1750 4050);
FORCEPROP 2 LAST CDS_SEC 1
J 0
(-1750 4050);
PAINT MONO (-1750 4050);
DISPLAY INVISIBLE (-1750 4050);
FORCEPROP 2 LAST CDS_LIB dev_discrete
J 0
(-1800 3850);
PAINT ORANGE (-1800 3850);
DISPLAY INVISIBLE (-1800 3850);
FORCEPROP 2 LAST CDS_LOCATION C5D52
J 0
(-1750 3950);
DISPLAY 0.617021 (-1750 3950);
PAINT AQUA (-1750 3950);
DISPLAY INVISIBLE (-1750 3950);
FORCEADD VCC_CORE..1
(-1800 4075);
FORCEPROP 3 LASTPIN (-1800 4025) SIG_NAME PVCCMCP_CPU0\g
J 0
(-1790 4035);
DISPLAY 0.659574 (-1790 4035);
PAINT MONO (-1790 4035);
DISPLAY INVISIBLE (-1790 4035);
FORCEPROP 1 LAST HDL_POWER PVCCMCP_CPU0
J 1
(-1800 4125);
DISPLAY 0.617021 (-1800 4125);
PAINT GREEN (-1800 4125);
FORCEPROP 1 LAST PATH I181
J 0
(-1750 4100);
DISPLAY 0.872340 (-1750 4100);
PAINT AQUA (-1750 4100);
DISPLAY INVISIBLE (-1750 4100);
FORCEPROP 2 LAST CDS_LIB mstr_symbols
J 0
(-1800 4075);
PAINT ORANGE (-1800 4075);
DISPLAY INVISIBLE (-1800 4075);
FORCEADD CAP..1
(-6850 1550);
FORCEPROP 0 LAST GROUP PWR_MLCC_CAP
J 0
(-6795 1352);
DISPLAY 0.638298 (-6795 1352);
PAINT BROWN (-6795 1352);
DISPLAY BOTH (-6795 1352);
FORCEPROP 1 LAST LOCATION C5P15
J 0
(-6800 1700);
DISPLAY 0.617021 (-6800 1700);
PAINT AQUA (-6800 1700);
FORCEPROP 1 LAST PACK_TYPE 0805
J 0
(-6800 1450);
DISPLAY 0.617021 (-6800 1450);
PAINT SKYBLUE (-6800 1450);
FORCEPROP 1 LASTPIN (-6850 1450) $PN 2
J 0
(-6840 1430);
DISPLAY 0.787234 (-6840 1430);
PAINT GREEN (-6840 1430);
FORCEPROP 1 LAST PART_NUMBER C95333-006
R 1
J 0
(-6900 1450);
DISPLAY 0.617021 (-6900 1450);
PAINT BLUE (-6900 1450);
FORCEPROP 1 LAST TOLERANCE 20%
J 0
(-6800 1550);
DISPLAY 0.617021 (-6800 1550);
PAINT SKYBLUE (-6800 1550);
FORCEPROP 1 LAST VALUE 47UF
J 0
(-6800 1650);
DISPLAY 0.617021 (-6800 1650);
PAINT SKYBLUE (-6800 1650);
FORCEPROP 1 LAST MATERIAL X6S
J 0
(-6800 1500);
DISPLAY 0.638298 (-6800 1500);
PAINT SKYBLUE (-6800 1500);
FORCEPROP 1 LAST VOLTAGE 4V
J 0
(-6800 1600);
DISPLAY 0.638298 (-6800 1600);
PAINT SKYBLUE (-6800 1600);
FORCEPROP 1 LASTPIN (-6850 1650) $PN 1
J 0
(-6840 1630);
DISPLAY 0.787234 (-6840 1630);
PAINT GREEN (-6840 1630);
FORCEPROP 2 LAST SEC_TYPE 0805
J 0
(-6800 1750);
DISPLAY 1.021277 (-6800 1750);
PAINT ORANGE (-6800 1750);
DISPLAY INVISIBLE (-6800 1750);
FORCEPROP 2 LAST SEC 1
J 0
(-6800 1750);
PAINT MONO (-6800 1750);
DISPLAY INVISIBLE (-6800 1750);
FORCEPROP 2 LAST BOM_COST PROC_SOCKET
J 0
(-6800 1750);
DISPLAY 1.021277 (-6800 1750);
PAINT ORANGE (-6800 1750);
DISPLAY INVISIBLE (-6800 1750);
FORCEPROP 2 LAST CDS_LIB mstr_discrete
J 0
(-6850 1550);
PAINT ORANGE (-6850 1550);
DISPLAY INVISIBLE (-6850 1550);
FORCEPROP 2 LAST CDS_LOCATION C5P15
J 0
(-6800 1650);
DISPLAY 0.617021 (-6800 1650);
PAINT AQUA (-6800 1650);
DISPLAY INVISIBLE (-6800 1650);
FORCEPROP 1 LAST PATH I187
J 0
(-6800 1700);
DISPLAY 0.978723 (-6800 1700);
PAINT WHITE (-6800 1700);
DISPLAY INVISIBLE (-6800 1700);
FORCEPROP 2 LAST ROOM PVCCIN_CPU0_DECAP_VR
J 0
(-6800 1700);
DISPLAY 1.021277 (-6800 1700);
PAINT ORANGE (-6800 1700);
DISPLAY INVISIBLE (-6800 1700);
FORCEADD CAP..1
(-6850 2250);
FORCEPROP 1 LAST MATERIAL X6S
J 0
(-6800 2200);
DISPLAY 0.638298 (-6800 2200);
PAINT SKYBLUE (-6800 2200);
FORCEPROP 1 LAST PACK_TYPE 0805
J 0
(-6800 2150);
DISPLAY 0.617021 (-6800 2150);
PAINT SKYBLUE (-6800 2150);
FORCEPROP 1 LASTPIN (-6850 2150) $PN 2
J 0
(-6840 2130);
DISPLAY 0.787234 (-6840 2130);
PAINT GREEN (-6840 2130);
FORCEPROP 1 LAST TOLERANCE 20%
J 0
(-6800 2300);
DISPLAY 0.617021 (-6800 2300);
PAINT SKYBLUE (-6800 2300);
FORCEPROP 1 LAST VOLTAGE 4V
J 0
(-6800 2250);
DISPLAY 0.638298 (-6800 2250);
PAINT SKYBLUE (-6800 2250);
FORCEPROP 1 LAST LOCATION C5P16
J 0
(-6800 2400);
DISPLAY 0.617021 (-6800 2400);
PAINT AQUA (-6800 2400);
FORCEPROP 0 LAST GROUP PWR_MLCC_CAP
J 0
(-6795 2052);
DISPLAY 0.638298 (-6795 2052);
PAINT BROWN (-6795 2052);
DISPLAY BOTH (-6795 2052);
FORCEPROP 1 LAST VALUE 47UF
J 0
(-6800 2350);
DISPLAY 0.617021 (-6800 2350);
PAINT SKYBLUE (-6800 2350);
FORCEPROP 1 LASTPIN (-6850 2350) $PN 1
J 0
(-6840 2330);
DISPLAY 0.787234 (-6840 2330);
PAINT GREEN (-6840 2330);
FORCEPROP 1 LAST PART_NUMBER C95333-006
R 1
J 0
(-6900 2150);
DISPLAY 0.617021 (-6900 2150);
PAINT BLUE (-6900 2150);
FORCEPROP 2 LAST SEC_TYPE 0805
J 0
(-6800 2450);
DISPLAY 1.021277 (-6800 2450);
PAINT ORANGE (-6800 2450);
DISPLAY INVISIBLE (-6800 2450);
FORCEPROP 2 LAST SEC 1
J 0
(-6800 2450);
PAINT MONO (-6800 2450);
DISPLAY INVISIBLE (-6800 2450);
FORCEPROP 2 LAST ROOM PVCCIN_CPU0_DECAP_VR
J 0
(-6800 2400);
DISPLAY 1.021277 (-6800 2400);
PAINT ORANGE (-6800 2400);
DISPLAY INVISIBLE (-6800 2400);
FORCEPROP 1 LAST PATH I188
J 0
(-6800 2400);
DISPLAY 0.978723 (-6800 2400);
PAINT WHITE (-6800 2400);
DISPLAY INVISIBLE (-6800 2400);
FORCEPROP 2 LAST CDS_LOCATION C5P16
J 0
(-6800 2350);
DISPLAY 0.617021 (-6800 2350);
PAINT AQUA (-6800 2350);
DISPLAY INVISIBLE (-6800 2350);
FORCEPROP 2 LAST CDS_LIB mstr_discrete
J 0
(-6850 2250);
PAINT ORANGE (-6850 2250);
DISPLAY INVISIBLE (-6850 2250);
FORCEPROP 2 LAST BOM_COST PROC_SOCKET
J 0
(-6800 2450);
DISPLAY 1.021277 (-6800 2450);
PAINT ORANGE (-6800 2450);
DISPLAY INVISIBLE (-6800 2450);
FORCEADD CAP..1
(-6550 1550);
FORCEPROP 1 LAST LOCATION C5P17
J 0
(-6500 1700);
DISPLAY 0.617021 (-6500 1700);
PAINT AQUA (-6500 1700);
FORCEPROP 1 LAST VALUE 47UF
J 0
(-6500 1650);
DISPLAY 0.617021 (-6500 1650);
PAINT SKYBLUE (-6500 1650);
FORCEPROP 1 LAST PART_NUMBER C95333-006
R 1
J 0
(-6600 1450);
DISPLAY 0.617021 (-6600 1450);
PAINT BLUE (-6600 1450);
FORCEPROP 1 LASTPIN (-6550 1450) $PN 2
J 0
(-6540 1430);
DISPLAY 0.787234 (-6540 1430);
PAINT GREEN (-6540 1430);
FORCEPROP 1 LAST PACK_TYPE 0805
J 0
(-6500 1450);
DISPLAY 0.617021 (-6500 1450);
PAINT SKYBLUE (-6500 1450);
FORCEPROP 1 LAST MATERIAL X6S
J 0
(-6500 1500);
DISPLAY 0.638298 (-6500 1500);
PAINT SKYBLUE (-6500 1500);
FORCEPROP 1 LAST TOLERANCE 20%
J 0
(-6500 1550);
DISPLAY 0.617021 (-6500 1550);
PAINT SKYBLUE (-6500 1550);
FORCEPROP 1 LAST VOLTAGE 4V
J 0
(-6500 1600);
DISPLAY 0.638298 (-6500 1600);
PAINT SKYBLUE (-6500 1600);
FORCEPROP 1 LASTPIN (-6550 1650) $PN 1
J 0
(-6540 1630);
DISPLAY 0.787234 (-6540 1630);
PAINT GREEN (-6540 1630);
FORCEPROP 0 LAST GROUP PWR_MLCC_CAP
J 0
(-6495 1402);
DISPLAY 0.638298 (-6495 1402);
PAINT BROWN (-6495 1402);
DISPLAY BOTH (-6495 1402);
FORCEPROP 2 LAST ROOM PVCCIN_CPU0_DECAP_VR
J 0
(-6500 1700);
DISPLAY 1.021277 (-6500 1700);
PAINT ORANGE (-6500 1700);
DISPLAY INVISIBLE (-6500 1700);
FORCEPROP 1 LAST PATH I190
J 0
(-6500 1700);
DISPLAY 0.978723 (-6500 1700);
PAINT WHITE (-6500 1700);
DISPLAY INVISIBLE (-6500 1700);
FORCEPROP 2 LAST CDS_LOCATION C5P17
J 0
(-6500 1650);
DISPLAY 0.617021 (-6500 1650);
PAINT AQUA (-6500 1650);
DISPLAY INVISIBLE (-6500 1650);
FORCEPROP 2 LAST CDS_LIB mstr_discrete
J 0
(-6550 1550);
PAINT ORANGE (-6550 1550);
DISPLAY INVISIBLE (-6550 1550);
FORCEPROP 2 LAST BOM_COST PROC_SOCKET
J 0
(-6500 1750);
DISPLAY 1.021277 (-6500 1750);
PAINT ORANGE (-6500 1750);
DISPLAY INVISIBLE (-6500 1750);
FORCEPROP 2 LAST SEC 1
J 0
(-6500 1750);
PAINT MONO (-6500 1750);
DISPLAY INVISIBLE (-6500 1750);
FORCEPROP 2 LAST SEC_TYPE 0805
J 0
(-6500 1750);
DISPLAY 1.021277 (-6500 1750);
PAINT ORANGE (-6500 1750);
DISPLAY INVISIBLE (-6500 1750);
FORCEADD PVCCIN_CPU0..1
(-6550 1150);
FORCEPROP 3 LASTPIN (-6550 1100) SIG_NAME PVCCIN_CPU0\g
J 0
(-6540 1110);
DISPLAY 0.659574 (-6540 1110);
PAINT MONO (-6540 1110);
DISPLAY INVISIBLE (-6540 1110);
FORCEPROP 1 LAST PATH I196
J 0
(-6500 1175);
DISPLAY 0.872340 (-6500 1175);
PAINT AQUA (-6500 1175);
DISPLAY INVISIBLE (-6500 1175);
FORCEPROP 1 LAST VOLTAGE 2.0V
J 0
(-6595 1107);
DISPLAY 0.340426 (-6595 1107);
PAINT SKYBLUE (-6595 1107);
DISPLAY INVISIBLE (-6595 1107);
FORCEPROP 2 LAST CDS_LIB mstr_symbols
J 0
(-6550 1150);
PAINT ORANGE (-6550 1150);
DISPLAY INVISIBLE (-6550 1150);
FORCEPROP 1 LAST BODY_TYPE PLUMBING
J 0
(-6595 1107);
DISPLAY 0.340426 (-6595 1107);
PAINT GREEN (-6595 1107);
DISPLAY INVISIBLE (-6595 1107);
FORCEPROP 1 LAST HDL_POWER PVCCIN_CPU0
J 1
(-6550 1200);
DISPLAY 0.872340 (-6550 1200);
PAINT GREEN (-6550 1200);
DISPLAY INVISIBLE (-6550 1200);
FORCEADD GND..1
(-1950 625);
FORCEPROP 3 LASTPIN (-1950 675) SIG_NAME GND\g
J 0
(-1940 685);
DISPLAY 0.659574 (-1940 685);
PAINT MONO (-1940 685);
DISPLAY INVISIBLE (-1940 685);
FORCEPROP 1 LAST VOLTAGE 0
J 0
(-1950 625);
PAINT SKYBLUE (-1950 625);
DISPLAY INVISIBLE (-1950 625);
FORCEPROP 1 LAST SIZE 1B
J 0
(-1875 575);
DISPLAY 0.893617 (-1875 575);
PAINT GREEN (-1875 575);
DISPLAY INVISIBLE (-1875 575);
FORCEPROP 2 LAST CDS_LIB mstr_symbols
J 0
(-1950 625);
PAINT ORANGE (-1950 625);
DISPLAY INVISIBLE (-1950 625);
FORCEPROP 1 LAST BODY_TYPE PLUMBING
J 0
(-1995 582);
DISPLAY 0.340426 (-1995 582);
PAINT GREEN (-1995 582);
DISPLAY INVISIBLE (-1995 582);
FORCEPROP 1 LAST PATH I20
J 0
(-1875 625);
DISPLAY 0.872340 (-1875 625);
PAINT AQUA (-1875 625);
DISPLAY INVISIBLE (-1875 625);
FORCEPROP 1 LAST HDL_POWER GND
J 0
(-1950 775);
DISPLAY 0.893617 (-1950 775);
PAINT GREEN (-1950 775);
DISPLAY INVISIBLE (-1950 775);
FORCEADD PVCCIN_CPU0..1
(-5350 2550);
FORCEPROP 3 LASTPIN (-5350 2500) SIG_NAME PVCCIN_CPU0\g
J 0
(-5340 2510);
DISPLAY 0.659574 (-5340 2510);
PAINT MONO (-5340 2510);
DISPLAY INVISIBLE (-5340 2510);
FORCEPROP 1 LAST PATH I203
J 0
(-5300 2575);
DISPLAY 0.872340 (-5300 2575);
PAINT AQUA (-5300 2575);
DISPLAY INVISIBLE (-5300 2575);
FORCEPROP 1 LAST VOLTAGE 2.0V
J 0
(-5395 2507);
DISPLAY 0.340426 (-5395 2507);
PAINT SKYBLUE (-5395 2507);
DISPLAY INVISIBLE (-5395 2507);
FORCEPROP 2 LAST CDS_LIB mstr_symbols
J 0
(-5350 2550);
PAINT ORANGE (-5350 2550);
DISPLAY INVISIBLE (-5350 2550);
FORCEPROP 1 LAST BODY_TYPE PLUMBING
J 0
(-5395 2507);
DISPLAY 0.340426 (-5395 2507);
PAINT GREEN (-5395 2507);
DISPLAY INVISIBLE (-5395 2507);
FORCEPROP 1 LAST HDL_POWER PVCCIN_CPU0
J 1
(-5350 2600);
DISPLAY 0.872340 (-5350 2600);
PAINT GREEN (-5350 2600);
DISPLAY INVISIBLE (-5350 2600);
FORCEADD GND..1
(-5950 1275);
FORCEPROP 3 LASTPIN (-5950 1325) SIG_NAME GND\g
J 0
(-5940 1335);
DISPLAY 0.659574 (-5940 1335);
PAINT MONO (-5940 1335);
DISPLAY INVISIBLE (-5940 1335);
FORCEPROP 1 LAST HDL_POWER GND
J 0
(-5950 1425);
DISPLAY 0.893617 (-5950 1425);
PAINT GREEN (-5950 1425);
DISPLAY INVISIBLE (-5950 1425);
FORCEPROP 1 LAST BODY_TYPE PLUMBING
J 0
(-5995 1232);
DISPLAY 0.340426 (-5995 1232);
PAINT GREEN (-5995 1232);
DISPLAY INVISIBLE (-5995 1232);
FORCEPROP 1 LAST SIZE 1B
J 0
(-5875 1225);
DISPLAY 0.893617 (-5875 1225);
PAINT GREEN (-5875 1225);
DISPLAY INVISIBLE (-5875 1225);
FORCEPROP 2 LAST CDS_LIB mstr_symbols
J 0
(-5950 1275);
PAINT ORANGE (-5950 1275);
DISPLAY INVISIBLE (-5950 1275);
FORCEPROP 1 LAST VOLTAGE 0
J 0
(-5950 1275);
PAINT SKYBLUE (-5950 1275);
DISPLAY INVISIBLE (-5950 1275);
FORCEPROP 1 LAST PATH I206
J 0
(-5875 1275);
DISPLAY 0.872340 (-5875 1275);
PAINT AQUA (-5875 1275);
DISPLAY INVISIBLE (-5875 1275);
FORCEADD PVCCIN_CPU0..1
(-5050 1850);
FORCEPROP 3 LASTPIN (-5050 1800) SIG_NAME PVCCIN_CPU0\g
J 0
(-5040 1810);
DISPLAY 0.659574 (-5040 1810);
PAINT MONO (-5040 1810);
DISPLAY INVISIBLE (-5040 1810);
FORCEPROP 1 LAST PATH I208
J 0
(-5000 1875);
DISPLAY 0.872340 (-5000 1875);
PAINT AQUA (-5000 1875);
DISPLAY INVISIBLE (-5000 1875);
FORCEPROP 1 LAST HDL_POWER PVCCIN_CPU0
J 1
(-5050 1900);
DISPLAY 0.872340 (-5050 1900);
PAINT GREEN (-5050 1900);
DISPLAY INVISIBLE (-5050 1900);
FORCEPROP 1 LAST BODY_TYPE PLUMBING
J 0
(-5095 1807);
DISPLAY 0.340426 (-5095 1807);
PAINT GREEN (-5095 1807);
DISPLAY INVISIBLE (-5095 1807);
FORCEPROP 2 LAST CDS_LIB mstr_symbols
J 0
(-5050 1850);
PAINT ORANGE (-5050 1850);
DISPLAY INVISIBLE (-5050 1850);
FORCEPROP 1 LAST VOLTAGE 2.0V
J 0
(-5095 1807);
DISPLAY 0.340426 (-5095 1807);
PAINT SKYBLUE (-5095 1807);
DISPLAY INVISIBLE (-5095 1807);
FORCEADD GND..1
(-3850 625);
FORCEPROP 3 LASTPIN (-3850 675) SIG_NAME GND\g
J 0
(-3840 685);
DISPLAY 0.659574 (-3840 685);
PAINT MONO (-3840 685);
DISPLAY INVISIBLE (-3840 685);
FORCEPROP 1 LAST HDL_POWER GND
J 0
(-3850 775);
DISPLAY 0.893617 (-3850 775);
PAINT GREEN (-3850 775);
DISPLAY INVISIBLE (-3850 775);
FORCEPROP 1 LAST PATH I21
J 0
(-3775 625);
DISPLAY 0.872340 (-3775 625);
PAINT AQUA (-3775 625);
DISPLAY INVISIBLE (-3775 625);
FORCEPROP 1 LAST BODY_TYPE PLUMBING
J 0
(-3895 582);
DISPLAY 0.340426 (-3895 582);
PAINT GREEN (-3895 582);
DISPLAY INVISIBLE (-3895 582);
FORCEPROP 1 LAST SIZE 1B
J 0
(-3775 575);
DISPLAY 0.893617 (-3775 575);
PAINT GREEN (-3775 575);
DISPLAY INVISIBLE (-3775 575);
FORCEPROP 2 LAST CDS_LIB mstr_symbols
J 0
(-3850 625);
PAINT MONO (-3850 625);
DISPLAY INVISIBLE (-3850 625);
FORCEPROP 1 LAST VOLTAGE 0
J 0
(-3850 625);
PAINT SKYBLUE (-3850 625);
DISPLAY INVISIBLE (-3850 625);
FORCEADD GND..1
(-5350 1975);
FORCEPROP 3 LASTPIN (-5350 2025) SIG_NAME GND\g
J 0
(-5340 2035);
DISPLAY 0.659574 (-5340 2035);
PAINT MONO (-5340 2035);
DISPLAY INVISIBLE (-5340 2035);
FORCEPROP 1 LAST HDL_POWER GND
J 0
(-5350 2125);
DISPLAY 0.893617 (-5350 2125);
PAINT GREEN (-5350 2125);
DISPLAY INVISIBLE (-5350 2125);
FORCEPROP 1 LAST BODY_TYPE PLUMBING
J 0
(-5395 1932);
DISPLAY 0.340426 (-5395 1932);
PAINT GREEN (-5395 1932);
DISPLAY INVISIBLE (-5395 1932);
FORCEPROP 2 LAST CDS_LIB mstr_symbols
J 0
(-5350 1975);
PAINT ORANGE (-5350 1975);
DISPLAY INVISIBLE (-5350 1975);
FORCEPROP 1 LAST SIZE 1B
J 0
(-5275 1925);
DISPLAY 0.893617 (-5275 1925);
PAINT GREEN (-5275 1925);
DISPLAY INVISIBLE (-5275 1925);
FORCEPROP 1 LAST VOLTAGE 0
J 0
(-5350 1975);
PAINT SKYBLUE (-5350 1975);
DISPLAY INVISIBLE (-5350 1975);
FORCEPROP 1 LAST PATH I210
J 0
(-5275 1975);
DISPLAY 0.872340 (-5275 1975);
PAINT AQUA (-5275 1975);
DISPLAY INVISIBLE (-5275 1975);
FORCEADD CAP..1
(-1150 1250);
FORCEPROP 1 LAST PACK_TYPE 0805
J 0
(-1100 1175);
DISPLAY 0.617021 (-1100 1175);
PAINT SKYBLUE (-1100 1175);
FORCEPROP 1 LAST TOLERANCE 20%
J 0
(-1100 1275);
DISPLAY 0.617021 (-1100 1275);
PAINT SKYBLUE (-1100 1275);
FORCEPROP 1 LASTPIN (-1150 1350) $PN 1
J 0
(-1140 1330);
DISPLAY 0.617021 (-1140 1330);
PAINT ORANGE (-1140 1330);
FORCEPROP 1 LASTPIN (-1150 1150) $PN 2
J 0
(-1140 1130);
DISPLAY 0.617021 (-1140 1130);
PAINT ORANGE (-1140 1130);
FORCEPROP 1 LAST VOLTAGE 4V
J 0
(-1100 1325);
DISPLAY 0.617021 (-1100 1325);
PAINT SKYBLUE (-1100 1325);
FORCEPROP 0 LAST GROUP PWR_MLCC_CAP
J 0
(-1094 1112);
DISPLAY 0.638298 (-1094 1112);
PAINT BROWN (-1094 1112);
DISPLAY BOTH (-1094 1112);
FORCEPROP 0 LAST NEW_MATERIAL X6S
J 0
(-1100 1000);
DISPLAY 0.638298 (-1100 1000);
PAINT BROWN (-1100 1000);
DISPLAY BOTH (-1100 1000);
FORCEPROP 1 LAST VALUE 100UF
J 0
(-1100 1375);
DISPLAY 0.617021 (-1100 1375);
PAINT SKYBLUE (-1100 1375);
FORCEPROP 1 LAST LOCATION C8W3
J 0
(-1100 1425);
DISPLAY 0.617021 (-1100 1425);
PAINT AQUA (-1100 1425);
FORCEPROP 0 LAST NEW_PN 078.1071T.M002
J 0
(-1100 1050);
DISPLAY 0.638298 (-1100 1050);
PAINT BROWN (-1100 1050);
DISPLAY BOTH (-1100 1050);
FORCEPROP 1 LAST PART_NUMBER 602433-112
J 0
(-1100 1225);
DISPLAY 0.617021 (-1100 1225);
PAINT BLUE (-1100 1225);
FORCEPROP 2 LAST CDS_LOCATION C8W3
J 0
(-1100 1350);
DISPLAY 0.617021 (-1100 1350);
PAINT AQUA (-1100 1350);
DISPLAY INVISIBLE (-1100 1350);
FORCEPROP 0 LAST CDS_SEC 1
J 0
(-1100 1400);
PAINT MONO (-1100 1400);
DISPLAY INVISIBLE (-1100 1400);
FORCEPROP 2 LAST CDS_LIB mstr_discrete
J 0
(-1150 1250);
PAINT MONO (-1150 1250);
DISPLAY INVISIBLE (-1150 1250);
FORCEPROP 2 LAST BOM_COST MEM_VRD_PVDDQ_CD
J 0
(-1100 1400);
PAINT MONO (-1100 1400);
DISPLAY INVISIBLE (-1100 1400);
FORCEPROP 2 LAST ROOM VDDQ_ABC_PWR_VR
J 0
(-1100 1400);
PAINT MONO (-1100 1400);
DISPLAY INVISIBLE (-1100 1400);
FORCEPROP 2 LAST SEC_TYPE 0805
J 0
(-1100 1450);
DISPLAY 1.021277 (-1100 1450);
PAINT ORANGE (-1100 1450);
DISPLAY INVISIBLE (-1100 1450);
FORCEPROP 2 LAST SEC 1
J 0
(-1100 1450);
DISPLAY 0.680851 (-1100 1450);
PAINT MONO (-1100 1450);
DISPLAY INVISIBLE (-1100 1450);
FORCEPROP 1 LAST MATERIAL X5R
J 0
(-1100 1150);
DISPLAY 0.617021 (-1100 1150);
PAINT SKYBLUE (-1100 1150);
DISPLAY INVISIBLE (-1100 1150);
FORCEPROP 1 LAST PATH I211
J 0
(-1100 1400);
DISPLAY 0.978723 (-1100 1400);
PAINT WHITE (-1100 1400);
DISPLAY INVISIBLE (-1100 1400);
FORCEADD GND..1
(-1150 1025);
FORCEPROP 3 LASTPIN (-1150 1075) SIG_NAME GND\g
J 0
(-1140 1085);
DISPLAY 0.659574 (-1140 1085);
PAINT MONO (-1140 1085);
DISPLAY INVISIBLE (-1140 1085);
FORCEPROP 1 LAST PATH I212
J 0
(-1075 1025);
DISPLAY 0.872340 (-1075 1025);
PAINT AQUA (-1075 1025);
DISPLAY INVISIBLE (-1075 1025);
FORCEPROP 1 LAST HDL_POWER GND
J 0
(-1150 1175);
DISPLAY 0.893617 (-1150 1175);
PAINT GREEN (-1150 1175);
DISPLAY INVISIBLE (-1150 1175);
FORCEPROP 1 LAST BODY_TYPE PLUMBING
J 0
(-1195 982);
DISPLAY 0.340426 (-1195 982);
PAINT GREEN (-1195 982);
DISPLAY INVISIBLE (-1195 982);
FORCEPROP 1 LAST SIZE 1B
J 0
(-1075 975);
DISPLAY 0.893617 (-1075 975);
PAINT GREEN (-1075 975);
DISPLAY INVISIBLE (-1075 975);
FORCEPROP 2 LAST CDS_LIB mstr_symbols
J 0
(-1150 1025);
PAINT ORANGE (-1150 1025);
DISPLAY INVISIBLE (-1150 1025);
FORCEPROP 1 LAST VOLTAGE 0
J 0
(-1150 1025);
PAINT SKYBLUE (-1150 1025);
DISPLAY INVISIBLE (-1150 1025);
FORCEADD PVCCIN_CPU0..1
(-1150 1500);
FORCEPROP 3 LASTPIN (-1150 1450) SIG_NAME PVCCIN_CPU0\g
J 0
(-1140 1460);
DISPLAY 0.659574 (-1140 1460);
PAINT MONO (-1140 1460);
DISPLAY INVISIBLE (-1140 1460);
FORCEPROP 1 LAST VOLTAGE 2.0V
J 0
(-1195 1457);
DISPLAY 0.340426 (-1195 1457);
PAINT SKYBLUE (-1195 1457);
DISPLAY INVISIBLE (-1195 1457);
FORCEPROP 2 LAST CDS_LIB mstr_symbols
J 0
(-1150 1500);
PAINT ORANGE (-1150 1500);
DISPLAY INVISIBLE (-1150 1500);
FORCEPROP 1 LAST BODY_TYPE PLUMBING
J 0
(-1195 1457);
DISPLAY 0.340426 (-1195 1457);
PAINT GREEN (-1195 1457);
DISPLAY INVISIBLE (-1195 1457);
FORCEPROP 1 LAST HDL_POWER PVCCIN_CPU0
J 1
(-1150 1550);
DISPLAY 0.872340 (-1150 1550);
PAINT GREEN (-1150 1550);
DISPLAY INVISIBLE (-1150 1550);
FORCEPROP 1 LAST PATH I213
J 0
(-1100 1525);
DISPLAY 0.872340 (-1100 1525);
PAINT AQUA (-1100 1525);
DISPLAY INVISIBLE (-1100 1525);
FORCEADD CAP..1
(-4150 950);
FORCEPROP 1 LAST MATERIAL X6S
J 0
(-4100 900);
DISPLAY 0.638298 (-4100 900);
PAINT SKYBLUE (-4100 900);
FORCEPROP 1 LAST TOLERANCE 20%
J 0
(-4100 950);
DISPLAY 0.617021 (-4100 950);
PAINT SKYBLUE (-4100 950);
FORCEPROP 1 LAST VOLTAGE 4V
J 0
(-4100 1000);
DISPLAY 0.638298 (-4100 1000);
PAINT SKYBLUE (-4100 1000);
FORCEPROP 1 LASTPIN (-4150 1050) $PN 1
J 0
(-4140 1030);
DISPLAY 0.617021 (-4140 1030);
PAINT GREEN (-4140 1030);
FORCEPROP 1 LASTPIN (-4150 850) $PN 2
J 0
(-4140 830);
DISPLAY 0.617021 (-4140 830);
PAINT GREEN (-4140 830);
FORCEPROP 1 LAST LOCATION C5P8
J 0
(-4100 1100);
DISPLAY 0.617021 (-4100 1100);
PAINT AQUA (-4100 1100);
FORCEPROP 1 LAST VALUE 22UF
J 0
(-4100 1050);
DISPLAY 0.617021 (-4100 1050);
PAINT SKYBLUE (-4100 1050);
FORCEPROP 0 LAST GROUP PWR_MLCC_CAP
J 0
(-4094 712);
DISPLAY 0.638298 (-4094 712);
PAINT BROWN (-4094 712);
DISPLAY BOTH (-4094 712);
FORCEPROP 1 LAST PACK_TYPE 0805LF
J 0
(-4100 800);
DISPLAY 0.617021 (-4100 800);
PAINT SKYBLUE (-4100 800);
FORCEPROP 1 LAST PART_NUMBER C95333-002
J 0
(-4100 850);
DISPLAY 0.617021 (-4100 850);
PAINT BLUE (-4100 850);
FORCEPROP 2 LAST ROOM PVCCIN_CPU0_DECAP_VR
J 0
(-4100 1100);
DISPLAY 1.021277 (-4100 1100);
PAINT ORANGE (-4100 1100);
DISPLAY INVISIBLE (-4100 1100);
FORCEPROP 2 LAST $SEC 1
J 0
(-4100 1150);
DISPLAY 0.680851 (-4100 1150);
PAINT MONO (-4100 1150);
DISPLAY INVISIBLE (-4100 1150);
FORCEPROP 2 LAST CDS_SEC 1
J 0
(-4100 1150);
DISPLAY 1.021277 (-4100 1150);
PAINT ORANGE (-4100 1150);
DISPLAY INVISIBLE (-4100 1150);
FORCEPROP 2 LAST BOM_COST PROC_SOCKET
J 0
(-4100 1150);
DISPLAY 1.021277 (-4100 1150);
PAINT ORANGE (-4100 1150);
DISPLAY INVISIBLE (-4100 1150);
FORCEPROP 2 LAST CDS_LIB mstr_discrete
J 0
(-4150 950);
PAINT ORANGE (-4150 950);
DISPLAY INVISIBLE (-4150 950);
FORCEPROP 1 LAST PATH I214
J 0
(-4100 1100);
DISPLAY 0.978723 (-4100 1100);
PAINT WHITE (-4100 1100);
DISPLAY INVISIBLE (-4100 1100);
FORCEPROP 2 LAST CDS_LOCATION C5P8
J 0
(-4100 1050);
DISPLAY 0.617021 (-4100 1050);
PAINT AQUA (-4100 1050);
DISPLAY INVISIBLE (-4100 1050);
FORCEADD CAP..1
(-3850 950);
FORCEPROP 1 LAST PACK_TYPE 0805LF
J 0
(-3800 800);
DISPLAY 0.617021 (-3800 800);
PAINT SKYBLUE (-3800 800);
FORCEPROP 1 LASTPIN (-3850 850) $PN 2
J 0
(-3840 830);
DISPLAY 0.617021 (-3840 830);
PAINT GREEN (-3840 830);
FORCEPROP 1 LASTPIN (-3850 1050) $PN 1
J 0
(-3840 1030);
DISPLAY 0.617021 (-3840 1030);
PAINT GREEN (-3840 1030);
FORCEPROP 1 LAST MATERIAL X6S
J 0
(-3800 900);
DISPLAY 0.638298 (-3800 900);
PAINT SKYBLUE (-3800 900);
FORCEPROP 0 LAST GROUP PWR_MLCC_CAP
J 0
(-3794 762);
DISPLAY 0.638298 (-3794 762);
PAINT BROWN (-3794 762);
DISPLAY BOTH (-3794 762);
FORCEPROP 1 LAST PART_NUMBER C95333-002
J 0
(-3800 850);
DISPLAY 0.617021 (-3800 850);
PAINT BLUE (-3800 850);
FORCEPROP 1 LAST TOLERANCE 20%
J 0
(-3800 950);
DISPLAY 0.617021 (-3800 950);
PAINT SKYBLUE (-3800 950);
FORCEPROP 1 LAST VOLTAGE 4V
J 0
(-3800 1000);
DISPLAY 0.638298 (-3800 1000);
PAINT SKYBLUE (-3800 1000);
FORCEPROP 1 LAST VALUE 22UF
J 0
(-3800 1050);
DISPLAY 0.617021 (-3800 1050);
PAINT SKYBLUE (-3800 1050);
FORCEPROP 1 LAST LOCATION C5P9
J 0
(-3800 1100);
DISPLAY 0.617021 (-3800 1100);
PAINT AQUA (-3800 1100);
FORCEPROP 2 LAST ROOM PVCCIN_CPU0_DECAP_VR
J 0
(-3800 1100);
DISPLAY 1.021277 (-3800 1100);
PAINT ORANGE (-3800 1100);
DISPLAY INVISIBLE (-3800 1100);
FORCEPROP 2 LAST $SEC 1
J 0
(-3800 1150);
DISPLAY 0.680851 (-3800 1150);
PAINT MONO (-3800 1150);
DISPLAY INVISIBLE (-3800 1150);
FORCEPROP 2 LAST CDS_SEC 1
J 0
(-3800 1150);
DISPLAY 1.021277 (-3800 1150);
PAINT ORANGE (-3800 1150);
DISPLAY INVISIBLE (-3800 1150);
FORCEPROP 2 LAST BOM_COST PROC_SOCKET
J 0
(-3800 1150);
DISPLAY 1.021277 (-3800 1150);
PAINT ORANGE (-3800 1150);
DISPLAY INVISIBLE (-3800 1150);
FORCEPROP 2 LAST CDS_LIB mstr_discrete
J 0
(-3850 950);
PAINT ORANGE (-3850 950);
DISPLAY INVISIBLE (-3850 950);
FORCEPROP 1 LAST PATH I215
J 0
(-3800 1100);
DISPLAY 0.978723 (-3800 1100);
PAINT WHITE (-3800 1100);
DISPLAY INVISIBLE (-3800 1100);
FORCEPROP 2 LAST CDS_LOCATION C5P9
J 0
(-3800 1050);
DISPLAY 0.617021 (-3800 1050);
PAINT AQUA (-3800 1050);
DISPLAY INVISIBLE (-3800 1050);
FORCEADD VCC_CORE..1
(-800 3375);
FORCEPROP 3 LASTPIN (-800 3325) SIG_NAME PVCCMCP_CPU0\g
J 0
(-790 3335);
DISPLAY 0.659574 (-790 3335);
PAINT MONO (-790 3335);
DISPLAY INVISIBLE (-790 3335);
FORCEPROP 1 LAST HDL_POWER PVCCMCP_CPU0
J 1
(-800 3425);
DISPLAY 0.617021 (-800 3425);
PAINT GREEN (-800 3425);
FORCEPROP 2 LAST CDS_LIB mstr_symbols
J 0
(-800 3375);
PAINT ORANGE (-800 3375);
DISPLAY INVISIBLE (-800 3375);
FORCEPROP 1 LAST PATH I216
J 0
(-750 3400);
DISPLAY 0.872340 (-750 3400);
PAINT AQUA (-750 3400);
DISPLAY INVISIBLE (-750 3400);
FORCEADD CAP_A..1
(-800 3150);
FORCEPROP 0 LAST GROUP PWR_MCP_CAP
J 0
(-750 2900);
DISPLAY 0.638298 (-750 2900);
PAINT BROWN (-750 2900);
DISPLAY BOTH (-750 2900);
FORCEPROP 1 LAST LOCATION C5W1
J 0
(-750 3250);
DISPLAY 0.617021 (-750 3250);
PAINT AQUA (-750 3250);
FORCEPROP 1 LAST VALUE 22.0UF
J 0
(-750 3200);
DISPLAY 0.617021 (-750 3200);
PAINT SKYBLUE (-750 3200);
FORCEPROP 1 LASTPIN (-800 3050) $PN 2
J 0
(-790 3030);
DISPLAY 0.787234 (-790 3030);
PAINT ORANGE (-790 3030);
FORCEPROP 1 LAST MATERIAL X6S
J 0
(-750 3050);
DISPLAY 0.617021 (-750 3050);
PAINT SKYBLUE (-750 3050);
FORCEPROP 1 LAST PART_NUMBER E15431-004
J 0
(-750 3000);
DISPLAY 0.617021 (-750 3000);
PAINT BLUE (-750 3000);
FORCEPROP 1 LAST PACK_TYPE 0603V
J 0
(-750 2950);
DISPLAY 0.617021 (-750 2950);
PAINT SKYBLUE (-750 2950);
FORCEPROP 1 LAST TOLERANCE 20%
J 0
(-750 3100);
DISPLAY 0.617021 (-750 3100);
PAINT SKYBLUE (-750 3100);
FORCEPROP 1 LAST VOLTAGE 4V
J 0
(-750 3150);
DISPLAY 0.617021 (-750 3150);
PAINT SKYBLUE (-750 3150);
FORCEPROP 1 LASTPIN (-800 3250) $PN 1
J 0
(-790 3230);
DISPLAY 0.787234 (-790 3230);
PAINT ORANGE (-790 3230);
FORCEPROP 2 LAST CDS_LOCATION C5W1
J 0
(-750 3250);
DISPLAY 0.617021 (-750 3250);
PAINT AQUA (-750 3250);
DISPLAY INVISIBLE (-750 3250);
FORCEPROP 2 LAST SEC_TYPE 0603V
J 0
(-750 3350);
DISPLAY 1.021277 (-750 3350);
PAINT ORANGE (-750 3350);
DISPLAY INVISIBLE (-750 3350);
FORCEPROP 2 LAST SEC 1
J 0
(-750 3350);
PAINT MONO (-750 3350);
DISPLAY INVISIBLE (-750 3350);
FORCEPROP 1 LAST PATH I217
J 0
(-750 3300);
DISPLAY 0.978723 (-750 3300);
PAINT WHITE (-750 3300);
DISPLAY INVISIBLE (-750 3300);
FORCEPROP 2 LAST BOM_COST PROC_SOCKET
J 0
(-750 3350);
DISPLAY 1.021277 (-750 3350);
PAINT ORANGE (-750 3350);
DISPLAY INVISIBLE (-750 3350);
FORCEPROP 2 LAST CDS_LIB dev_discrete
J 0
(-800 3150);
PAINT ORANGE (-800 3150);
DISPLAY INVISIBLE (-800 3150);
FORCEPROP 2 LAST ROOM PVCCIN_CPU0_DECAP_VR
J 0
(-750 3300);
DISPLAY 1.021277 (-750 3300);
PAINT ORANGE (-750 3300);
DISPLAY INVISIBLE (-750 3300);
FORCEADD CAP_A..1
(-550 3150);
FORCEPROP 1 LAST PART_NUMBER E15431-004
J 0
(-500 3000);
DISPLAY 0.617021 (-500 3000);
PAINT BLUE (-500 3000);
FORCEPROP 0 LAST GROUP PWR_MCP_CAP
J 0
(-500 2850);
DISPLAY 0.638298 (-500 2850);
PAINT BROWN (-500 2850);
DISPLAY BOTH (-500 2850);
FORCEPROP 1 LAST VALUE 22.0UF
J 0
(-500 3200);
DISPLAY 0.617021 (-500 3200);
PAINT SKYBLUE (-500 3200);
FORCEPROP 1 LASTPIN (-550 3250) $PN 1
J 0
(-540 3230);
DISPLAY 0.787234 (-540 3230);
PAINT ORANGE (-540 3230);
FORCEPROP 1 LAST LOCATION C5W2
J 0
(-500 3250);
DISPLAY 0.617021 (-500 3250);
PAINT AQUA (-500 3250);
FORCEPROP 1 LAST TOLERANCE 20%
J 0
(-500 3100);
DISPLAY 0.617021 (-500 3100);
PAINT SKYBLUE (-500 3100);
FORCEPROP 1 LAST MATERIAL X6S
J 0
(-500 3050);
DISPLAY 0.617021 (-500 3050);
PAINT SKYBLUE (-500 3050);
FORCEPROP 1 LASTPIN (-550 3050) $PN 2
J 0
(-540 3030);
DISPLAY 0.787234 (-540 3030);
PAINT ORANGE (-540 3030);
FORCEPROP 1 LAST VOLTAGE 4V
J 0
(-500 3150);
DISPLAY 0.617021 (-500 3150);
PAINT SKYBLUE (-500 3150);
FORCEPROP 1 LAST PACK_TYPE 0603V
J 0
(-500 2950);
DISPLAY 0.617021 (-500 2950);
PAINT SKYBLUE (-500 2950);
FORCEPROP 2 LAST ROOM PVCCIN_CPU0_DECAP_VR
J 0
(-500 3300);
DISPLAY 1.021277 (-500 3300);
PAINT ORANGE (-500 3300);
DISPLAY INVISIBLE (-500 3300);
FORCEPROP 2 LAST CDS_LIB dev_discrete
J 0
(-550 3150);
PAINT ORANGE (-550 3150);
DISPLAY INVISIBLE (-550 3150);
FORCEPROP 2 LAST BOM_COST PROC_SOCKET
J 0
(-500 3350);
DISPLAY 1.021277 (-500 3350);
PAINT ORANGE (-500 3350);
DISPLAY INVISIBLE (-500 3350);
FORCEPROP 1 LAST PATH I218
J 0
(-500 3300);
DISPLAY 0.978723 (-500 3300);
PAINT WHITE (-500 3300);
DISPLAY INVISIBLE (-500 3300);
FORCEPROP 2 LAST SEC 1
J 0
(-500 3350);
PAINT MONO (-500 3350);
DISPLAY INVISIBLE (-500 3350);
FORCEPROP 2 LAST SEC_TYPE 0603V
J 0
(-500 3350);
DISPLAY 1.021277 (-500 3350);
PAINT ORANGE (-500 3350);
DISPLAY INVISIBLE (-500 3350);
FORCEPROP 2 LAST CDS_LOCATION C5W2
J 0
(-500 3250);
DISPLAY 0.617021 (-500 3250);
PAINT AQUA (-500 3250);
DISPLAY INVISIBLE (-500 3250);
FORCEADD GND..1
(-800 2875);
FORCEPROP 3 LASTPIN (-800 2925) SIG_NAME GND\g
J 0
(-790 2935);
DISPLAY 0.659574 (-790 2935);
PAINT MONO (-790 2935);
DISPLAY INVISIBLE (-790 2935);
FORCEPROP 1 LAST VOLTAGE 0
J 0
(-800 2875);
PAINT SKYBLUE (-800 2875);
DISPLAY INVISIBLE (-800 2875);
FORCEPROP 1 LAST SIZE 1B
J 0
(-725 2825);
DISPLAY 0.893617 (-725 2825);
PAINT GREEN (-725 2825);
DISPLAY INVISIBLE (-725 2825);
FORCEPROP 2 LAST CDS_LIB mstr_symbols
J 0
(-800 2875);
PAINT ORANGE (-800 2875);
DISPLAY INVISIBLE (-800 2875);
FORCEPROP 1 LAST BODY_TYPE PLUMBING
J 0
(-845 2832);
DISPLAY 0.340426 (-845 2832);
PAINT GREEN (-845 2832);
DISPLAY INVISIBLE (-845 2832);
FORCEPROP 1 LAST HDL_POWER GND
J 0
(-800 3025);
DISPLAY 0.893617 (-800 3025);
PAINT GREEN (-800 3025);
DISPLAY INVISIBLE (-800 3025);
FORCEPROP 1 LAST PATH I219
J 0
(-725 2875);
DISPLAY 0.872340 (-725 2875);
PAINT AQUA (-725 2875);
DISPLAY INVISIBLE (-725 2875);
FORCEADD CAP..1
(-4750 2225);
FORCEPROP 0 LAST NEW_MATERIAL X6S
J 0
(-4700 2025);
DISPLAY 0.638298 (-4700 2025);
PAINT BROWN (-4700 2025);
DISPLAY BOTH (-4700 2025);
FORCEPROP 0 LAST NEW_PN 078.1071T.M002
J 0
(-4700 2075);
DISPLAY 0.638298 (-4700 2075);
PAINT BROWN (-4700 2075);
DISPLAY BOTH (-4700 2075);
FORCEPROP 1 LAST VALUE 100UF
J 0
(-4650 2300);
DISPLAY 0.617021 (-4650 2300);
PAINT SKYBLUE (-4650 2300);
FORCEPROP 1 LASTPIN (-4750 2325) $PN 1
J 0
(-4740 2305);
DISPLAY 0.617021 (-4740 2305);
PAINT ORANGE (-4740 2305);
FORCEPROP 1 LAST LOCATION C5P29
J 0
(-4650 2350);
DISPLAY 0.617021 (-4650 2350);
PAINT AQUA (-4650 2350);
FORCEPROP 1 LASTPIN (-4750 2125) $PN 2
J 0
(-4740 2130);
DISPLAY 0.617021 (-4740 2130);
PAINT ORANGE (-4740 2130);
FORCEPROP 1 LAST VOLTAGE 4V
J 0
(-4650 2250);
DISPLAY 0.617021 (-4650 2250);
PAINT SKYBLUE (-4650 2250);
FORCEPROP 1 LAST TOLERANCE 20%
J 0
(-4650 2200);
DISPLAY 0.617021 (-4650 2200);
PAINT SKYBLUE (-4650 2200);
FORCEPROP 1 LAST PART_NUMBER 602433-112
R 1
J 0
(-4675 2150);
DISPLAY 0.617021 (-4675 2150);
PAINT BLUE (-4675 2150);
FORCEPROP 1 LAST PACK_TYPE 0805
J 0
(-4650 2150);
DISPLAY 0.617021 (-4650 2150);
PAINT SKYBLUE (-4650 2150);
FORCEPROP 0 LAST GROUP PWR_MCP_CAP
J 0
(-4700 1975);
DISPLAY 0.638298 (-4700 1975);
PAINT BROWN (-4700 1975);
DISPLAY BOTH (-4700 1975);
FORCEPROP 1 LAST MATERIAL X5R
J 0
(-4700 2125);
DISPLAY 0.617021 (-4700 2125);
PAINT SKYBLUE (-4700 2125);
DISPLAY INVISIBLE (-4700 2125);
FORCEPROP 2 LAST SEC 1
J 0
(-4700 2425);
DISPLAY 0.680851 (-4700 2425);
PAINT MONO (-4700 2425);
DISPLAY INVISIBLE (-4700 2425);
FORCEPROP 2 LAST SEC_TYPE 0805
J 0
(-4700 2425);
DISPLAY 1.021277 (-4700 2425);
PAINT ORANGE (-4700 2425);
DISPLAY INVISIBLE (-4700 2425);
FORCEPROP 2 LAST ROOM VDDQ_ABC_PWR_VR
J 0
(-4700 2375);
PAINT MONO (-4700 2375);
DISPLAY INVISIBLE (-4700 2375);
FORCEPROP 2 LAST BOM_COST MEM_VRD_PVDDQ_CD
J 0
(-4700 2375);
PAINT MONO (-4700 2375);
DISPLAY INVISIBLE (-4700 2375);
FORCEPROP 2 LAST CDS_LIB mstr_discrete
J 0
(-4750 2225);
PAINT MONO (-4750 2225);
DISPLAY INVISIBLE (-4750 2225);
FORCEPROP 0 LAST CDS_SEC 1
J 0
(-4700 2375);
PAINT MONO (-4700 2375);
DISPLAY INVISIBLE (-4700 2375);
FORCEPROP 1 LAST PATH I220
J 0
(-4700 2375);
DISPLAY 0.978723 (-4700 2375);
PAINT WHITE (-4700 2375);
DISPLAY INVISIBLE (-4700 2375);
FORCEPROP 2 LAST CDS_LOCATION C5P29
J 0
(-4700 2325);
DISPLAY 0.617021 (-4700 2325);
PAINT AQUA (-4700 2325);
DISPLAY INVISIBLE (-4700 2325);
FORCEADD CAP..1
(-4500 2225);
FORCEPROP 0 LAST NEW_PN 078.1071T.M002
J 0
(-4450 1925);
DISPLAY 0.638298 (-4450 1925);
PAINT BROWN (-4450 1925);
DISPLAY BOTH (-4450 1925);
FORCEPROP 1 LAST LOCATION C5P30
J 0
(-4400 2350);
DISPLAY 0.617021 (-4400 2350);
PAINT AQUA (-4400 2350);
FORCEPROP 1 LAST VALUE 100UF
J 0
(-4400 2300);
DISPLAY 0.617021 (-4400 2300);
PAINT SKYBLUE (-4400 2300);
FORCEPROP 1 LAST PACK_TYPE 0805
J 0
(-4400 2150);
DISPLAY 0.617021 (-4400 2150);
PAINT SKYBLUE (-4400 2150);
FORCEPROP 1 LASTPIN (-4500 2325) $PN 1
J 0
(-4490 2305);
DISPLAY 0.617021 (-4490 2305);
PAINT ORANGE (-4490 2305);
FORCEPROP 1 LASTPIN (-4500 2125) $PN 2
J 0
(-4490 2130);
DISPLAY 0.617021 (-4490 2130);
PAINT ORANGE (-4490 2130);
FORCEPROP 1 LAST VOLTAGE 4V
J 0
(-4400 2250);
DISPLAY 0.617021 (-4400 2250);
PAINT SKYBLUE (-4400 2250);
FORCEPROP 1 LAST PART_NUMBER 602433-112
R 1
J 0
(-4425 2150);
DISPLAY 0.617021 (-4425 2150);
PAINT BLUE (-4425 2150);
FORCEPROP 1 LAST TOLERANCE 20%
J 0
(-4400 2200);
DISPLAY 0.617021 (-4400 2200);
PAINT SKYBLUE (-4400 2200);
FORCEPROP 0 LAST GROUP PWR_MCP_CAP
J 0
(-4450 1825);
DISPLAY 0.638298 (-4450 1825);
PAINT BROWN (-4450 1825);
DISPLAY BOTH (-4450 1825);
FORCEPROP 0 LAST NEW_MATERIAL X6S
J 0
(-4450 1875);
DISPLAY 0.638298 (-4450 1875);
PAINT BROWN (-4450 1875);
DISPLAY BOTH (-4450 1875);
FORCEPROP 2 LAST CDS_LOCATION C5P30
J 0
(-4450 2325);
DISPLAY 0.617021 (-4450 2325);
PAINT AQUA (-4450 2325);
DISPLAY INVISIBLE (-4450 2325);
FORCEPROP 1 LAST PATH I221
J 0
(-4450 2375);
DISPLAY 0.978723 (-4450 2375);
PAINT WHITE (-4450 2375);
DISPLAY INVISIBLE (-4450 2375);
FORCEPROP 1 LAST MATERIAL X5R
J 0
(-4450 2125);
DISPLAY 0.617021 (-4450 2125);
PAINT SKYBLUE (-4450 2125);
DISPLAY INVISIBLE (-4450 2125);
FORCEPROP 2 LAST SEC 1
J 0
(-4450 2425);
DISPLAY 0.680851 (-4450 2425);
PAINT MONO (-4450 2425);
DISPLAY INVISIBLE (-4450 2425);
FORCEPROP 2 LAST SEC_TYPE 0805
J 0
(-4450 2425);
DISPLAY 1.021277 (-4450 2425);
PAINT ORANGE (-4450 2425);
DISPLAY INVISIBLE (-4450 2425);
FORCEPROP 2 LAST ROOM VDDQ_ABC_PWR_VR
J 0
(-4450 2375);
PAINT MONO (-4450 2375);
DISPLAY INVISIBLE (-4450 2375);
FORCEPROP 2 LAST BOM_COST MEM_VRD_PVDDQ_CD
J 0
(-4450 2375);
PAINT MONO (-4450 2375);
DISPLAY INVISIBLE (-4450 2375);
FORCEPROP 2 LAST CDS_LIB mstr_discrete
J 0
(-4500 2225);
PAINT MONO (-4500 2225);
DISPLAY INVISIBLE (-4500 2225);
FORCEPROP 0 LAST CDS_SEC 1
J 0
(-4450 2375);
PAINT MONO (-4450 2375);
DISPLAY INVISIBLE (-4450 2375);
FORCEADD CAP..1
(-4000 2225);
FORCEPROP 0 LAST NEW_PN 078.1071T.M002
J 0
(-3950 1925);
DISPLAY 0.638298 (-3950 1925);
PAINT BROWN (-3950 1925);
DISPLAY BOTH (-3950 1925);
FORCEPROP 1 LAST PACK_TYPE 0805
J 0
(-3900 2150);
DISPLAY 0.617021 (-3900 2150);
PAINT SKYBLUE (-3900 2150);
FORCEPROP 1 LASTPIN (-4000 2125) $PN 2
J 0
(-3990 2130);
DISPLAY 0.617021 (-3990 2130);
PAINT ORANGE (-3990 2130);
FORCEPROP 1 LASTPIN (-4000 2325) $PN 1
J 0
(-3990 2305);
DISPLAY 0.617021 (-3990 2305);
PAINT ORANGE (-3990 2305);
FORCEPROP 1 LAST TOLERANCE 20%
J 0
(-3900 2200);
DISPLAY 0.617021 (-3900 2200);
PAINT SKYBLUE (-3900 2200);
FORCEPROP 0 LAST GROUP PWR_MCP_CAP
J 0
(-3950 1825);
DISPLAY 0.638298 (-3950 1825);
PAINT BROWN (-3950 1825);
DISPLAY BOTH (-3950 1825);
FORCEPROP 1 LAST LOCATION C5P19
J 0
(-3900 2350);
DISPLAY 0.617021 (-3900 2350);
PAINT AQUA (-3900 2350);
FORCEPROP 1 LAST VALUE 100UF
J 0
(-3900 2300);
DISPLAY 0.617021 (-3900 2300);
PAINT SKYBLUE (-3900 2300);
FORCEPROP 1 LAST PART_NUMBER 602433-112
R 1
J 0
(-3925 2150);
DISPLAY 0.617021 (-3925 2150);
PAINT BLUE (-3925 2150);
FORCEPROP 1 LAST VOLTAGE 4V
J 0
(-3900 2250);
DISPLAY 0.617021 (-3900 2250);
PAINT SKYBLUE (-3900 2250);
FORCEPROP 0 LAST NEW_MATERIAL X6S
J 0
(-3950 1875);
DISPLAY 0.638298 (-3950 1875);
PAINT BROWN (-3950 1875);
DISPLAY BOTH (-3950 1875);
FORCEPROP 2 LAST CDS_LOCATION C5P19
J 0
(-3950 2325);
DISPLAY 0.617021 (-3950 2325);
PAINT AQUA (-3950 2325);
DISPLAY INVISIBLE (-3950 2325);
FORCEPROP 1 LAST PATH I222
J 0
(-3950 2375);
DISPLAY 0.978723 (-3950 2375);
PAINT WHITE (-3950 2375);
DISPLAY INVISIBLE (-3950 2375);
FORCEPROP 0 LAST CDS_SEC 1
J 0
(-3950 2375);
PAINT MONO (-3950 2375);
DISPLAY INVISIBLE (-3950 2375);
FORCEPROP 2 LAST CDS_LIB mstr_discrete
J 0
(-4000 2225);
PAINT MONO (-4000 2225);
DISPLAY INVISIBLE (-4000 2225);
FORCEPROP 2 LAST BOM_COST MEM_VRD_PVDDQ_CD
J 0
(-3950 2375);
PAINT MONO (-3950 2375);
DISPLAY INVISIBLE (-3950 2375);
FORCEPROP 2 LAST ROOM VDDQ_ABC_PWR_VR
J 0
(-3950 2375);
PAINT MONO (-3950 2375);
DISPLAY INVISIBLE (-3950 2375);
FORCEPROP 2 LAST SEC_TYPE 0805
J 0
(-3950 2425);
DISPLAY 1.021277 (-3950 2425);
PAINT ORANGE (-3950 2425);
DISPLAY INVISIBLE (-3950 2425);
FORCEPROP 2 LAST SEC 1
J 0
(-3950 2425);
DISPLAY 0.680851 (-3950 2425);
PAINT MONO (-3950 2425);
DISPLAY INVISIBLE (-3950 2425);
FORCEPROP 1 LAST MATERIAL X5R
J 0
(-3950 2125);
DISPLAY 0.617021 (-3950 2125);
PAINT SKYBLUE (-3950 2125);
DISPLAY INVISIBLE (-3950 2125);
FORCEADD CAP..1
(-4250 2225);
FORCEPROP 0 LAST NEW_MATERIAL X6S
J 0
(-4200 2025);
DISPLAY 0.638298 (-4200 2025);
PAINT BROWN (-4200 2025);
DISPLAY BOTH (-4200 2025);
FORCEPROP 0 LAST NEW_PN 078.1071T.M002
J 0
(-4200 2075);
DISPLAY 0.638298 (-4200 2075);
PAINT BROWN (-4200 2075);
DISPLAY BOTH (-4200 2075);
FORCEPROP 1 LASTPIN (-4250 2325) $PN 1
J 0
(-4240 2305);
DISPLAY 0.617021 (-4240 2305);
PAINT ORANGE (-4240 2305);
FORCEPROP 1 LASTPIN (-4250 2125) $PN 2
J 0
(-4240 2130);
DISPLAY 0.617021 (-4240 2130);
PAINT ORANGE (-4240 2130);
FORCEPROP 1 LAST LOCATION C4P4
J 0
(-4150 2350);
DISPLAY 0.617021 (-4150 2350);
PAINT AQUA (-4150 2350);
FORCEPROP 1 LAST PACK_TYPE 0805
J 0
(-4150 2150);
DISPLAY 0.617021 (-4150 2150);
PAINT SKYBLUE (-4150 2150);
FORCEPROP 1 LAST TOLERANCE 20%
J 0
(-4150 2200);
DISPLAY 0.617021 (-4150 2200);
PAINT SKYBLUE (-4150 2200);
FORCEPROP 1 LAST VALUE 100UF
J 0
(-4150 2300);
DISPLAY 0.617021 (-4150 2300);
PAINT SKYBLUE (-4150 2300);
FORCEPROP 1 LAST PART_NUMBER 602433-112
R 1
J 0
(-4175 2150);
DISPLAY 0.617021 (-4175 2150);
PAINT BLUE (-4175 2150);
FORCEPROP 1 LAST VOLTAGE 4V
J 0
(-4150 2250);
DISPLAY 0.617021 (-4150 2250);
PAINT SKYBLUE (-4150 2250);
FORCEPROP 0 LAST GROUP PWR_MCP_CAP
J 0
(-4200 1975);
DISPLAY 0.638298 (-4200 1975);
PAINT BROWN (-4200 1975);
DISPLAY BOTH (-4200 1975);
FORCEPROP 1 LAST PATH I223
J 0
(-4200 2375);
DISPLAY 0.978723 (-4200 2375);
PAINT WHITE (-4200 2375);
DISPLAY INVISIBLE (-4200 2375);
FORCEPROP 1 LAST MATERIAL X5R
J 0
(-4200 2125);
DISPLAY 0.617021 (-4200 2125);
PAINT SKYBLUE (-4200 2125);
DISPLAY INVISIBLE (-4200 2125);
FORCEPROP 2 LAST SEC 1
J 0
(-4200 2425);
DISPLAY 0.680851 (-4200 2425);
PAINT MONO (-4200 2425);
DISPLAY INVISIBLE (-4200 2425);
FORCEPROP 2 LAST SEC_TYPE 0805
J 0
(-4200 2425);
DISPLAY 1.021277 (-4200 2425);
PAINT ORANGE (-4200 2425);
DISPLAY INVISIBLE (-4200 2425);
FORCEPROP 2 LAST ROOM VDDQ_ABC_PWR_VR
J 0
(-4200 2375);
PAINT MONO (-4200 2375);
DISPLAY INVISIBLE (-4200 2375);
FORCEPROP 2 LAST BOM_COST MEM_VRD_PVDDQ_CD
J 0
(-4200 2375);
PAINT MONO (-4200 2375);
DISPLAY INVISIBLE (-4200 2375);
FORCEPROP 2 LAST CDS_LIB mstr_discrete
J 0
(-4250 2225);
PAINT MONO (-4250 2225);
DISPLAY INVISIBLE (-4250 2225);
FORCEPROP 0 LAST CDS_SEC 1
J 0
(-4200 2375);
PAINT MONO (-4200 2375);
DISPLAY INVISIBLE (-4200 2375);
FORCEPROP 2 LAST CDS_LOCATION C4P4
J 0
(-4200 2325);
DISPLAY 0.617021 (-4200 2325);
PAINT AQUA (-4200 2325);
DISPLAY INVISIBLE (-4200 2325);
FORCEADD CAP..1
(-3750 2225);
FORCEPROP 1 LAST PACK_TYPE 0805
J 0
(-3650 2150);
DISPLAY 0.617021 (-3650 2150);
PAINT SKYBLUE (-3650 2150);
FORCEPROP 1 LASTPIN (-3750 2125) $PN 2
J 0
(-3740 2130);
DISPLAY 0.617021 (-3740 2130);
PAINT ORANGE (-3740 2130);
FORCEPROP 1 LAST TOLERANCE 20%
J 0
(-3650 2200);
DISPLAY 0.617021 (-3650 2200);
PAINT SKYBLUE (-3650 2200);
FORCEPROP 1 LAST LOCATION C4P7
J 0
(-3650 2350);
DISPLAY 0.617021 (-3650 2350);
PAINT AQUA (-3650 2350);
FORCEPROP 1 LAST VOLTAGE 4V
J 0
(-3650 2250);
DISPLAY 0.617021 (-3650 2250);
PAINT SKYBLUE (-3650 2250);
FORCEPROP 1 LASTPIN (-3750 2325) $PN 1
J 0
(-3740 2305);
DISPLAY 0.617021 (-3740 2305);
PAINT ORANGE (-3740 2305);
FORCEPROP 1 LAST PART_NUMBER 602433-112
R 1
J 0
(-3675 2150);
DISPLAY 0.617021 (-3675 2150);
PAINT BLUE (-3675 2150);
FORCEPROP 1 LAST VALUE 100UF
J 0
(-3650 2300);
DISPLAY 0.617021 (-3650 2300);
PAINT SKYBLUE (-3650 2300);
FORCEPROP 0 LAST NEW_MATERIAL X6S
J 0
(-3700 2025);
DISPLAY 0.638298 (-3700 2025);
PAINT BROWN (-3700 2025);
DISPLAY BOTH (-3700 2025);
FORCEPROP 0 LAST GROUP PWR_MCP_CAP
J 0
(-3700 1975);
DISPLAY 0.638298 (-3700 1975);
PAINT BROWN (-3700 1975);
DISPLAY BOTH (-3700 1975);
FORCEPROP 0 LAST NEW_PN 078.1071T.M002
J 0
(-3700 2075);
DISPLAY 0.638298 (-3700 2075);
PAINT BROWN (-3700 2075);
DISPLAY BOTH (-3700 2075);
FORCEPROP 1 LAST PATH I224
J 0
(-3700 2375);
DISPLAY 0.978723 (-3700 2375);
PAINT WHITE (-3700 2375);
DISPLAY INVISIBLE (-3700 2375);
FORCEPROP 0 LAST CDS_SEC 1
J 0
(-3700 2375);
PAINT MONO (-3700 2375);
DISPLAY INVISIBLE (-3700 2375);
FORCEPROP 2 LAST CDS_LIB mstr_discrete
J 0
(-3750 2225);
PAINT MONO (-3750 2225);
DISPLAY INVISIBLE (-3750 2225);
FORCEPROP 2 LAST BOM_COST MEM_VRD_PVDDQ_CD
J 0
(-3700 2375);
PAINT MONO (-3700 2375);
DISPLAY INVISIBLE (-3700 2375);
FORCEPROP 2 LAST ROOM VDDQ_ABC_PWR_VR
J 0
(-3700 2375);
PAINT MONO (-3700 2375);
DISPLAY INVISIBLE (-3700 2375);
FORCEPROP 2 LAST SEC_TYPE 0805
J 0
(-3700 2425);
DISPLAY 1.021277 (-3700 2425);
PAINT ORANGE (-3700 2425);
DISPLAY INVISIBLE (-3700 2425);
FORCEPROP 2 LAST SEC 1
J 0
(-3700 2425);
DISPLAY 0.680851 (-3700 2425);
PAINT MONO (-3700 2425);
DISPLAY INVISIBLE (-3700 2425);
FORCEPROP 1 LAST MATERIAL X5R
J 0
(-3700 2125);
DISPLAY 0.617021 (-3700 2125);
PAINT SKYBLUE (-3700 2125);
DISPLAY INVISIBLE (-3700 2125);
FORCEPROP 2 LAST CDS_LOCATION C4P7
J 0
(-3700 2325);
DISPLAY 0.617021 (-3700 2325);
PAINT AQUA (-3700 2325);
DISPLAY INVISIBLE (-3700 2325);
FORCEADD CAP..1
(-3500 2225);
FORCEPROP 1 LAST LOCATION C4P3
J 0
(-3400 2350);
DISPLAY 0.617021 (-3400 2350);
PAINT AQUA (-3400 2350);
FORCEPROP 1 LASTPIN (-3500 2325) $PN 1
J 0
(-3490 2305);
DISPLAY 0.617021 (-3490 2305);
PAINT ORANGE (-3490 2305);
FORCEPROP 1 LASTPIN (-3500 2125) $PN 2
J 0
(-3490 2130);
DISPLAY 0.617021 (-3490 2130);
PAINT ORANGE (-3490 2130);
FORCEPROP 1 LAST PART_NUMBER 602433-112
R 1
J 0
(-3425 2150);
DISPLAY 0.617021 (-3425 2150);
PAINT BLUE (-3425 2150);
FORCEPROP 1 LAST VOLTAGE 4V
J 0
(-3400 2250);
DISPLAY 0.617021 (-3400 2250);
PAINT SKYBLUE (-3400 2250);
FORCEPROP 1 LAST TOLERANCE 20%
J 0
(-3400 2200);
DISPLAY 0.617021 (-3400 2200);
PAINT SKYBLUE (-3400 2200);
FORCEPROP 1 LAST PACK_TYPE 0805
J 0
(-3400 2150);
DISPLAY 0.617021 (-3400 2150);
PAINT SKYBLUE (-3400 2150);
FORCEPROP 0 LAST NEW_PN 078.1071T.M002
J 0
(-3450 1925);
DISPLAY 0.638298 (-3450 1925);
PAINT BROWN (-3450 1925);
DISPLAY BOTH (-3450 1925);
FORCEPROP 0 LAST NEW_MATERIAL X6S
J 0
(-3450 1875);
DISPLAY 0.638298 (-3450 1875);
PAINT BROWN (-3450 1875);
DISPLAY BOTH (-3450 1875);
FORCEPROP 0 LAST GROUP PWR_MCP_CAP
J 0
(-3450 1825);
DISPLAY 0.638298 (-3450 1825);
PAINT BROWN (-3450 1825);
DISPLAY BOTH (-3450 1825);
FORCEPROP 1 LAST VALUE 100UF
J 0
(-3400 2300);
DISPLAY 0.617021 (-3400 2300);
PAINT SKYBLUE (-3400 2300);
FORCEPROP 2 LAST CDS_LOCATION C4P3
J 0
(-3450 2325);
DISPLAY 0.617021 (-3450 2325);
PAINT AQUA (-3450 2325);
DISPLAY INVISIBLE (-3450 2325);
FORCEPROP 1 LAST PATH I225
J 0
(-3450 2375);
DISPLAY 0.978723 (-3450 2375);
PAINT WHITE (-3450 2375);
DISPLAY INVISIBLE (-3450 2375);
FORCEPROP 0 LAST CDS_SEC 1
J 0
(-3450 2375);
PAINT MONO (-3450 2375);
DISPLAY INVISIBLE (-3450 2375);
FORCEPROP 2 LAST CDS_LIB mstr_discrete
J 0
(-3500 2225);
PAINT MONO (-3500 2225);
DISPLAY INVISIBLE (-3500 2225);
FORCEPROP 2 LAST BOM_COST MEM_VRD_PVDDQ_CD
J 0
(-3450 2375);
PAINT MONO (-3450 2375);
DISPLAY INVISIBLE (-3450 2375);
FORCEPROP 2 LAST ROOM VDDQ_ABC_PWR_VR
J 0
(-3450 2375);
PAINT MONO (-3450 2375);
DISPLAY INVISIBLE (-3450 2375);
FORCEPROP 2 LAST SEC_TYPE 0805
J 0
(-3450 2425);
DISPLAY 1.021277 (-3450 2425);
PAINT ORANGE (-3450 2425);
DISPLAY INVISIBLE (-3450 2425);
FORCEPROP 2 LAST SEC 1
J 0
(-3450 2425);
DISPLAY 0.680851 (-3450 2425);
PAINT MONO (-3450 2425);
DISPLAY INVISIBLE (-3450 2425);
FORCEPROP 1 LAST MATERIAL X5R
J 0
(-3450 2125);
DISPLAY 0.617021 (-3450 2125);
PAINT SKYBLUE (-3450 2125);
DISPLAY INVISIBLE (-3450 2125);
FORCEADD CAP..1
(-3250 2225);
FORCEPROP 1 LASTPIN (-3250 2325) $PN 1
J 0
(-3240 2305);
DISPLAY 0.617021 (-3240 2305);
PAINT ORANGE (-3240 2305);
FORCEPROP 1 LASTPIN (-3250 2125) $PN 2
J 0
(-3240 2130);
DISPLAY 0.617021 (-3240 2130);
PAINT ORANGE (-3240 2130);
FORCEPROP 1 LAST LOCATION C5P10
J 0
(-3150 2350);
DISPLAY 0.617021 (-3150 2350);
PAINT AQUA (-3150 2350);
FORCEPROP 1 LAST VALUE 100UF
J 0
(-3150 2300);
DISPLAY 0.617021 (-3150 2300);
PAINT SKYBLUE (-3150 2300);
FORCEPROP 1 LAST VOLTAGE 4V
J 0
(-3150 2250);
DISPLAY 0.617021 (-3150 2250);
PAINT SKYBLUE (-3150 2250);
FORCEPROP 1 LAST TOLERANCE 20%
J 0
(-3150 2200);
DISPLAY 0.617021 (-3150 2200);
PAINT SKYBLUE (-3150 2200);
FORCEPROP 0 LAST GROUP PWR_MCP_CAP
J 0
(-3200 1975);
DISPLAY 0.638298 (-3200 1975);
PAINT BROWN (-3200 1975);
DISPLAY BOTH (-3200 1975);
FORCEPROP 0 LAST NEW_MATERIAL X6S
J 0
(-3200 2025);
DISPLAY 0.638298 (-3200 2025);
PAINT BROWN (-3200 2025);
DISPLAY BOTH (-3200 2025);
FORCEPROP 0 LAST NEW_PN 078.1071T.M002
J 0
(-3200 2075);
DISPLAY 0.638298 (-3200 2075);
PAINT BROWN (-3200 2075);
DISPLAY BOTH (-3200 2075);
FORCEPROP 1 LAST PACK_TYPE 0805
J 0
(-3150 2150);
DISPLAY 0.617021 (-3150 2150);
PAINT SKYBLUE (-3150 2150);
FORCEPROP 1 LAST PART_NUMBER 602433-112
R 1
J 0
(-3175 2150);
DISPLAY 0.617021 (-3175 2150);
PAINT BLUE (-3175 2150);
FORCEPROP 1 LAST PATH I226
J 0
(-3200 2375);
DISPLAY 0.978723 (-3200 2375);
PAINT WHITE (-3200 2375);
DISPLAY INVISIBLE (-3200 2375);
FORCEPROP 1 LAST MATERIAL X5R
J 0
(-3200 2125);
DISPLAY 0.617021 (-3200 2125);
PAINT SKYBLUE (-3200 2125);
DISPLAY INVISIBLE (-3200 2125);
FORCEPROP 2 LAST SEC 1
J 0
(-3200 2425);
DISPLAY 0.680851 (-3200 2425);
PAINT MONO (-3200 2425);
DISPLAY INVISIBLE (-3200 2425);
FORCEPROP 2 LAST SEC_TYPE 0805
J 0
(-3200 2425);
DISPLAY 1.021277 (-3200 2425);
PAINT ORANGE (-3200 2425);
DISPLAY INVISIBLE (-3200 2425);
FORCEPROP 2 LAST ROOM VDDQ_ABC_PWR_VR
J 0
(-3200 2375);
PAINT MONO (-3200 2375);
DISPLAY INVISIBLE (-3200 2375);
FORCEPROP 2 LAST BOM_COST MEM_VRD_PVDDQ_CD
J 0
(-3200 2375);
PAINT MONO (-3200 2375);
DISPLAY INVISIBLE (-3200 2375);
FORCEPROP 2 LAST CDS_LIB mstr_discrete
J 0
(-3250 2225);
PAINT MONO (-3250 2225);
DISPLAY INVISIBLE (-3250 2225);
FORCEPROP 0 LAST CDS_SEC 1
J 0
(-3200 2375);
PAINT MONO (-3200 2375);
DISPLAY INVISIBLE (-3200 2375);
FORCEPROP 2 LAST CDS_LOCATION C5P10
J 0
(-3200 2325);
DISPLAY 0.617021 (-3200 2325);
PAINT AQUA (-3200 2325);
DISPLAY INVISIBLE (-3200 2325);
FORCEADD CAP..1
(-3000 2225);
FORCEPROP 1 LAST VOLTAGE 4V
J 0
(-2900 2250);
DISPLAY 0.617021 (-2900 2250);
PAINT SKYBLUE (-2900 2250);
FORCEPROP 1 LAST PART_NUMBER 602433-112
R 1
J 0
(-2925 2150);
DISPLAY 0.617021 (-2925 2150);
PAINT BLUE (-2925 2150);
FORCEPROP 1 LAST VALUE 100UF
J 0
(-2900 2300);
DISPLAY 0.617021 (-2900 2300);
PAINT SKYBLUE (-2900 2300);
FORCEPROP 1 LASTPIN (-3000 2325) $PN 1
J 0
(-2990 2305);
DISPLAY 0.617021 (-2990 2305);
PAINT ORANGE (-2990 2305);
FORCEPROP 1 LAST LOCATION C5P11
J 0
(-2900 2350);
DISPLAY 0.617021 (-2900 2350);
PAINT AQUA (-2900 2350);
FORCEPROP 1 LAST PACK_TYPE 0805
J 0
(-2900 2150);
DISPLAY 0.617021 (-2900 2150);
PAINT SKYBLUE (-2900 2150);
FORCEPROP 1 LASTPIN (-3000 2125) $PN 2
J 0
(-2990 2130);
DISPLAY 0.617021 (-2990 2130);
PAINT ORANGE (-2990 2130);
FORCEPROP 1 LAST TOLERANCE 20%
J 0
(-2900 2200);
DISPLAY 0.617021 (-2900 2200);
PAINT SKYBLUE (-2900 2200);
FORCEPROP 0 LAST GROUP PWR_MCP_CAP
J 0
(-2950 1825);
DISPLAY 0.638298 (-2950 1825);
PAINT BROWN (-2950 1825);
DISPLAY BOTH (-2950 1825);
FORCEPROP 0 LAST NEW_MATERIAL X6S
J 0
(-2950 1875);
DISPLAY 0.638298 (-2950 1875);
PAINT BROWN (-2950 1875);
DISPLAY BOTH (-2950 1875);
FORCEPROP 0 LAST NEW_PN 078.1071T.M002
J 0
(-2950 1925);
DISPLAY 0.638298 (-2950 1925);
PAINT BROWN (-2950 1925);
DISPLAY BOTH (-2950 1925);
FORCEPROP 2 LAST CDS_LOCATION C5P11
J 0
(-2950 2325);
DISPLAY 0.617021 (-2950 2325);
PAINT AQUA (-2950 2325);
DISPLAY INVISIBLE (-2950 2325);
FORCEPROP 0 LAST CDS_SEC 1
J 0
(-2950 2375);
PAINT MONO (-2950 2375);
DISPLAY INVISIBLE (-2950 2375);
FORCEPROP 2 LAST CDS_LIB mstr_discrete
J 0
(-3000 2225);
PAINT MONO (-3000 2225);
DISPLAY INVISIBLE (-3000 2225);
FORCEPROP 2 LAST BOM_COST MEM_VRD_PVDDQ_CD
J 0
(-2950 2375);
PAINT MONO (-2950 2375);
DISPLAY INVISIBLE (-2950 2375);
FORCEPROP 2 LAST ROOM VDDQ_ABC_PWR_VR
J 0
(-2950 2375);
PAINT MONO (-2950 2375);
DISPLAY INVISIBLE (-2950 2375);
FORCEPROP 2 LAST SEC_TYPE 0805
J 0
(-2950 2425);
DISPLAY 1.021277 (-2950 2425);
PAINT ORANGE (-2950 2425);
DISPLAY INVISIBLE (-2950 2425);
FORCEPROP 2 LAST SEC 1
J 0
(-2950 2425);
DISPLAY 0.680851 (-2950 2425);
PAINT MONO (-2950 2425);
DISPLAY INVISIBLE (-2950 2425);
FORCEPROP 1 LAST MATERIAL X5R
J 0
(-2950 2125);
DISPLAY 0.617021 (-2950 2125);
PAINT SKYBLUE (-2950 2125);
DISPLAY INVISIBLE (-2950 2125);
FORCEPROP 1 LAST PATH I227
J 0
(-2950 2375);
DISPLAY 0.978723 (-2950 2375);
PAINT WHITE (-2950 2375);
DISPLAY INVISIBLE (-2950 2375);
FORCEADD CAP..1
(-2500 2225);
FORCEPROP 0 LAST NEW_PN 078.1071T.M002
J 0
(-2450 1925);
DISPLAY 0.638298 (-2450 1925);
PAINT BROWN (-2450 1925);
DISPLAY BOTH (-2450 1925);
FORCEPROP 1 LASTPIN (-2500 2125) $PN 2
J 0
(-2490 2130);
DISPLAY 0.617021 (-2490 2130);
PAINT ORANGE (-2490 2130);
FORCEPROP 1 LASTPIN (-2500 2325) $PN 1
J 0
(-2490 2305);
DISPLAY 0.617021 (-2490 2305);
PAINT ORANGE (-2490 2305);
FORCEPROP 1 LAST LOCATION C5P18
J 0
(-2400 2350);
DISPLAY 0.617021 (-2400 2350);
PAINT AQUA (-2400 2350);
FORCEPROP 1 LAST VALUE 100UF
J 0
(-2400 2300);
DISPLAY 0.617021 (-2400 2300);
PAINT SKYBLUE (-2400 2300);
FORCEPROP 1 LAST PACK_TYPE 0805
J 0
(-2400 2150);
DISPLAY 0.617021 (-2400 2150);
PAINT SKYBLUE (-2400 2150);
FORCEPROP 1 LAST TOLERANCE 20%
J 0
(-2400 2200);
DISPLAY 0.617021 (-2400 2200);
PAINT SKYBLUE (-2400 2200);
FORCEPROP 1 LAST VOLTAGE 4V
J 0
(-2400 2250);
DISPLAY 0.617021 (-2400 2250);
PAINT SKYBLUE (-2400 2250);
FORCEPROP 1 LAST PART_NUMBER 602433-112
R 1
J 0
(-2425 2150);
DISPLAY 0.617021 (-2425 2150);
PAINT BLUE (-2425 2150);
FORCEPROP 0 LAST NEW_MATERIAL X6S
J 0
(-2450 1875);
DISPLAY 0.638298 (-2450 1875);
PAINT BROWN (-2450 1875);
DISPLAY BOTH (-2450 1875);
FORCEPROP 0 LAST GROUP PWR_MCP_CAP
J 0
(-2450 1825);
DISPLAY 0.638298 (-2450 1825);
PAINT BROWN (-2450 1825);
DISPLAY BOTH (-2450 1825);
FORCEPROP 2 LAST CDS_LOCATION C5P18
J 0
(-2450 2325);
DISPLAY 0.617021 (-2450 2325);
PAINT AQUA (-2450 2325);
DISPLAY INVISIBLE (-2450 2325);
FORCEPROP 1 LAST PATH I228
J 0
(-2450 2375);
DISPLAY 0.978723 (-2450 2375);
PAINT WHITE (-2450 2375);
DISPLAY INVISIBLE (-2450 2375);
FORCEPROP 0 LAST CDS_SEC 1
J 0
(-2450 2375);
PAINT MONO (-2450 2375);
DISPLAY INVISIBLE (-2450 2375);
FORCEPROP 2 LAST CDS_LIB mstr_discrete
J 0
(-2500 2225);
PAINT MONO (-2500 2225);
DISPLAY INVISIBLE (-2500 2225);
FORCEPROP 2 LAST BOM_COST MEM_VRD_PVDDQ_CD
J 0
(-2450 2375);
PAINT MONO (-2450 2375);
DISPLAY INVISIBLE (-2450 2375);
FORCEPROP 2 LAST ROOM VDDQ_ABC_PWR_VR
J 0
(-2450 2375);
PAINT MONO (-2450 2375);
DISPLAY INVISIBLE (-2450 2375);
FORCEPROP 2 LAST SEC_TYPE 0805
J 0
(-2450 2425);
DISPLAY 1.021277 (-2450 2425);
PAINT ORANGE (-2450 2425);
DISPLAY INVISIBLE (-2450 2425);
FORCEPROP 2 LAST SEC 1
J 0
(-2450 2425);
DISPLAY 0.680851 (-2450 2425);
PAINT MONO (-2450 2425);
DISPLAY INVISIBLE (-2450 2425);
FORCEPROP 1 LAST MATERIAL X5R
J 0
(-2450 2125);
DISPLAY 0.617021 (-2450 2125);
PAINT SKYBLUE (-2450 2125);
DISPLAY INVISIBLE (-2450 2125);
FORCEADD CAP..1
(-2750 2225);
FORCEPROP 0 LAST NEW_PN 078.1071T.M002
J 0
(-2700 2075);
DISPLAY 0.638298 (-2700 2075);
PAINT BROWN (-2700 2075);
DISPLAY BOTH (-2700 2075);
FORCEPROP 0 LAST GROUP PWR_MCP_CAP
J 0
(-2700 1975);
DISPLAY 0.638298 (-2700 1975);
PAINT BROWN (-2700 1975);
DISPLAY BOTH (-2700 1975);
FORCEPROP 1 LAST PACK_TYPE 0805
J 0
(-2650 2150);
DISPLAY 0.617021 (-2650 2150);
PAINT SKYBLUE (-2650 2150);
FORCEPROP 1 LAST TOLERANCE 20%
J 0
(-2650 2200);
DISPLAY 0.617021 (-2650 2200);
PAINT SKYBLUE (-2650 2200);
FORCEPROP 1 LAST PART_NUMBER 602433-112
R 1
J 0
(-2675 2150);
DISPLAY 0.617021 (-2675 2150);
PAINT BLUE (-2675 2150);
FORCEPROP 1 LAST LOCATION C5P28
J 0
(-2650 2350);
DISPLAY 0.617021 (-2650 2350);
PAINT AQUA (-2650 2350);
FORCEPROP 1 LASTPIN (-2750 2325) $PN 1
J 0
(-2740 2305);
DISPLAY 0.617021 (-2740 2305);
PAINT ORANGE (-2740 2305);
FORCEPROP 1 LAST VALUE 100UF
J 0
(-2650 2300);
DISPLAY 0.617021 (-2650 2300);
PAINT SKYBLUE (-2650 2300);
FORCEPROP 1 LASTPIN (-2750 2125) $PN 2
J 0
(-2740 2130);
DISPLAY 0.617021 (-2740 2130);
PAINT ORANGE (-2740 2130);
FORCEPROP 1 LAST VOLTAGE 4V
J 0
(-2650 2250);
DISPLAY 0.617021 (-2650 2250);
PAINT SKYBLUE (-2650 2250);
FORCEPROP 0 LAST NEW_MATERIAL X6S
J 0
(-2700 2025);
DISPLAY 0.638298 (-2700 2025);
PAINT BROWN (-2700 2025);
DISPLAY BOTH (-2700 2025);
FORCEPROP 1 LAST PATH I229
J 0
(-2700 2375);
DISPLAY 0.978723 (-2700 2375);
PAINT WHITE (-2700 2375);
DISPLAY INVISIBLE (-2700 2375);
FORCEPROP 1 LAST MATERIAL X5R
J 0
(-2700 2125);
DISPLAY 0.617021 (-2700 2125);
PAINT SKYBLUE (-2700 2125);
DISPLAY INVISIBLE (-2700 2125);
FORCEPROP 2 LAST SEC 1
J 0
(-2700 2425);
DISPLAY 0.680851 (-2700 2425);
PAINT MONO (-2700 2425);
DISPLAY INVISIBLE (-2700 2425);
FORCEPROP 2 LAST SEC_TYPE 0805
J 0
(-2700 2425);
DISPLAY 1.021277 (-2700 2425);
PAINT ORANGE (-2700 2425);
DISPLAY INVISIBLE (-2700 2425);
FORCEPROP 2 LAST ROOM VDDQ_ABC_PWR_VR
J 0
(-2700 2375);
PAINT MONO (-2700 2375);
DISPLAY INVISIBLE (-2700 2375);
FORCEPROP 2 LAST BOM_COST MEM_VRD_PVDDQ_CD
J 0
(-2700 2375);
PAINT MONO (-2700 2375);
DISPLAY INVISIBLE (-2700 2375);
FORCEPROP 2 LAST CDS_LIB mstr_discrete
J 0
(-2750 2225);
PAINT MONO (-2750 2225);
DISPLAY INVISIBLE (-2750 2225);
FORCEPROP 0 LAST CDS_SEC 1
J 0
(-2700 2375);
PAINT MONO (-2700 2375);
DISPLAY INVISIBLE (-2700 2375);
FORCEPROP 2 LAST CDS_LOCATION C5P28
J 0
(-2700 2325);
DISPLAY 0.617021 (-2700 2325);
PAINT AQUA (-2700 2325);
DISPLAY INVISIBLE (-2700 2325);
FORCEADD CAP..1
(-2000 2225);
FORCEPROP 1 LAST PART_NUMBER 602433-112
R 1
J 0
(-1925 2150);
DISPLAY 0.617021 (-1925 2150);
PAINT BLUE (-1925 2150);
FORCEPROP 1 LAST VOLTAGE 4V
J 0
(-1900 2250);
DISPLAY 0.617021 (-1900 2250);
PAINT SKYBLUE (-1900 2250);
FORCEPROP 1 LASTPIN (-2000 2125) $PN 2
J 0
(-1990 2130);
DISPLAY 0.617021 (-1990 2130);
PAINT ORANGE (-1990 2130);
FORCEPROP 1 LASTPIN (-2000 2325) $PN 1
J 0
(-1990 2305);
DISPLAY 0.617021 (-1990 2305);
PAINT ORANGE (-1990 2305);
FORCEPROP 1 LAST TOLERANCE 20%
J 0
(-1900 2200);
DISPLAY 0.617021 (-1900 2200);
PAINT SKYBLUE (-1900 2200);
FORCEPROP 1 LAST VALUE 100UF
J 0
(-1900 2300);
DISPLAY 0.617021 (-1900 2300);
PAINT SKYBLUE (-1900 2300);
FORCEPROP 1 LAST PACK_TYPE 0805
J 0
(-1900 2150);
DISPLAY 0.617021 (-1900 2150);
PAINT SKYBLUE (-1900 2150);
FORCEPROP 1 LAST LOCATION C4P2
J 0
(-1900 2350);
DISPLAY 0.617021 (-1900 2350);
PAINT AQUA (-1900 2350);
FORCEPROP 0 LAST NEW_PN 078.1071T.M002
J 0
(-1950 1925);
DISPLAY 0.638298 (-1950 1925);
PAINT BROWN (-1950 1925);
DISPLAY BOTH (-1950 1925);
FORCEPROP 0 LAST NEW_MATERIAL X6S
J 0
(-1950 1875);
DISPLAY 0.638298 (-1950 1875);
PAINT BROWN (-1950 1875);
DISPLAY BOTH (-1950 1875);
FORCEPROP 0 LAST GROUP PWR_MCP_CAP
J 0
(-1950 1825);
DISPLAY 0.638298 (-1950 1825);
PAINT BROWN (-1950 1825);
DISPLAY BOTH (-1950 1825);
FORCEPROP 2 LAST CDS_LOCATION C4P2
J 0
(-1950 2325);
DISPLAY 0.617021 (-1950 2325);
PAINT AQUA (-1950 2325);
DISPLAY INVISIBLE (-1950 2325);
FORCEPROP 1 LAST PATH I230
J 0
(-1950 2375);
DISPLAY 0.978723 (-1950 2375);
PAINT WHITE (-1950 2375);
DISPLAY INVISIBLE (-1950 2375);
FORCEPROP 1 LAST MATERIAL X5R
J 0
(-1950 2125);
DISPLAY 0.617021 (-1950 2125);
PAINT SKYBLUE (-1950 2125);
DISPLAY INVISIBLE (-1950 2125);
FORCEPROP 2 LAST SEC 1
J 0
(-1950 2425);
DISPLAY 0.680851 (-1950 2425);
PAINT MONO (-1950 2425);
DISPLAY INVISIBLE (-1950 2425);
FORCEPROP 2 LAST SEC_TYPE 0805
J 0
(-1950 2425);
DISPLAY 1.021277 (-1950 2425);
PAINT ORANGE (-1950 2425);
DISPLAY INVISIBLE (-1950 2425);
FORCEPROP 2 LAST ROOM VDDQ_ABC_PWR_VR
J 0
(-1950 2375);
PAINT MONO (-1950 2375);
DISPLAY INVISIBLE (-1950 2375);
FORCEPROP 2 LAST BOM_COST MEM_VRD_PVDDQ_CD
J 0
(-1950 2375);
PAINT MONO (-1950 2375);
DISPLAY INVISIBLE (-1950 2375);
FORCEPROP 2 LAST CDS_LIB mstr_discrete
J 0
(-2000 2225);
PAINT MONO (-2000 2225);
DISPLAY INVISIBLE (-2000 2225);
FORCEPROP 0 LAST CDS_SEC 1
J 0
(-1950 2375);
PAINT MONO (-1950 2375);
DISPLAY INVISIBLE (-1950 2375);
FORCEADD CAP..1
(-2250 2225);
FORCEPROP 0 LAST NEW_PN 078.1071T.M002
J 0
(-2200 2075);
DISPLAY 0.638298 (-2200 2075);
PAINT BROWN (-2200 2075);
DISPLAY BOTH (-2200 2075);
FORCEPROP 1 LAST PART_NUMBER 602433-112
R 1
J 0
(-2175 2150);
DISPLAY 0.617021 (-2175 2150);
PAINT BLUE (-2175 2150);
FORCEPROP 1 LASTPIN (-2250 2325) $PN 1
J 0
(-2240 2305);
DISPLAY 0.617021 (-2240 2305);
PAINT ORANGE (-2240 2305);
FORCEPROP 1 LASTPIN (-2250 2125) $PN 2
J 0
(-2240 2130);
DISPLAY 0.617021 (-2240 2130);
PAINT ORANGE (-2240 2130);
FORCEPROP 1 LAST VALUE 100UF
J 0
(-2150 2300);
DISPLAY 0.617021 (-2150 2300);
PAINT SKYBLUE (-2150 2300);
FORCEPROP 1 LAST LOCATION C5P31
J 0
(-2150 2350);
DISPLAY 0.617021 (-2150 2350);
PAINT AQUA (-2150 2350);
FORCEPROP 1 LAST VOLTAGE 4V
J 0
(-2150 2250);
DISPLAY 0.617021 (-2150 2250);
PAINT SKYBLUE (-2150 2250);
FORCEPROP 1 LAST PACK_TYPE 0805
J 0
(-2150 2150);
DISPLAY 0.617021 (-2150 2150);
PAINT SKYBLUE (-2150 2150);
FORCEPROP 0 LAST NEW_MATERIAL X6S
J 0
(-2200 2025);
DISPLAY 0.638298 (-2200 2025);
PAINT BROWN (-2200 2025);
DISPLAY BOTH (-2200 2025);
FORCEPROP 0 LAST GROUP PWR_MCP_CAP
J 0
(-2200 1975);
DISPLAY 0.638298 (-2200 1975);
PAINT BROWN (-2200 1975);
DISPLAY BOTH (-2200 1975);
FORCEPROP 1 LAST TOLERANCE 20%
J 0
(-2150 2200);
DISPLAY 0.617021 (-2150 2200);
PAINT SKYBLUE (-2150 2200);
FORCEPROP 0 LAST CDS_SEC 1
J 0
(-2200 2375);
PAINT MONO (-2200 2375);
DISPLAY INVISIBLE (-2200 2375);
FORCEPROP 2 LAST CDS_LIB mstr_discrete
J 0
(-2250 2225);
PAINT MONO (-2250 2225);
DISPLAY INVISIBLE (-2250 2225);
FORCEPROP 2 LAST BOM_COST MEM_VRD_PVDDQ_CD
J 0
(-2200 2375);
PAINT MONO (-2200 2375);
DISPLAY INVISIBLE (-2200 2375);
FORCEPROP 2 LAST ROOM VDDQ_ABC_PWR_VR
J 0
(-2200 2375);
PAINT MONO (-2200 2375);
DISPLAY INVISIBLE (-2200 2375);
FORCEPROP 2 LAST SEC_TYPE 0805
J 0
(-2200 2425);
DISPLAY 1.021277 (-2200 2425);
PAINT ORANGE (-2200 2425);
DISPLAY INVISIBLE (-2200 2425);
FORCEPROP 2 LAST SEC 1
J 0
(-2200 2425);
DISPLAY 0.680851 (-2200 2425);
PAINT MONO (-2200 2425);
DISPLAY INVISIBLE (-2200 2425);
FORCEPROP 1 LAST MATERIAL X5R
J 0
(-2200 2125);
DISPLAY 0.617021 (-2200 2125);
PAINT SKYBLUE (-2200 2125);
DISPLAY INVISIBLE (-2200 2125);
FORCEPROP 1 LAST PATH I231
J 0
(-2200 2375);
DISPLAY 0.978723 (-2200 2375);
PAINT WHITE (-2200 2375);
DISPLAY INVISIBLE (-2200 2375);
FORCEPROP 2 LAST CDS_LOCATION C5P31
J 0
(-2200 2325);
DISPLAY 0.617021 (-2200 2325);
PAINT AQUA (-2200 2325);
DISPLAY INVISIBLE (-2200 2325);
FORCEADD CAP..1
(-1500 2225);
FORCEPROP 0 LAST NEW_PN 078.1071T.M002
J 0
(-1450 1925);
DISPLAY 0.638298 (-1450 1925);
PAINT BROWN (-1450 1925);
DISPLAY BOTH (-1450 1925);
FORCEPROP 0 LAST GROUP PWR_MCP_CAP
J 0
(-1450 1825);
DISPLAY 0.638298 (-1450 1825);
PAINT BROWN (-1450 1825);
DISPLAY BOTH (-1450 1825);
FORCEPROP 1 LAST VALUE 100UF
J 0
(-1400 2300);
DISPLAY 0.617021 (-1400 2300);
PAINT SKYBLUE (-1400 2300);
FORCEPROP 1 LAST PACK_TYPE 0805
J 0
(-1400 2150);
DISPLAY 0.617021 (-1400 2150);
PAINT SKYBLUE (-1400 2150);
FORCEPROP 1 LASTPIN (-1500 2125) $PN 2
J 0
(-1490 2130);
DISPLAY 0.617021 (-1490 2130);
PAINT ORANGE (-1490 2130);
FORCEPROP 1 LASTPIN (-1500 2325) $PN 1
J 0
(-1490 2305);
DISPLAY 0.617021 (-1490 2305);
PAINT ORANGE (-1490 2305);
FORCEPROP 1 LAST LOCATION C5P13
J 0
(-1400 2350);
DISPLAY 0.617021 (-1400 2350);
PAINT AQUA (-1400 2350);
FORCEPROP 1 LAST TOLERANCE 20%
J 0
(-1400 2200);
DISPLAY 0.617021 (-1400 2200);
PAINT SKYBLUE (-1400 2200);
FORCEPROP 1 LAST PART_NUMBER 602433-112
R 1
J 0
(-1425 2150);
DISPLAY 0.617021 (-1425 2150);
PAINT BLUE (-1425 2150);
FORCEPROP 1 LAST VOLTAGE 4V
J 0
(-1400 2250);
DISPLAY 0.617021 (-1400 2250);
PAINT SKYBLUE (-1400 2250);
FORCEPROP 0 LAST NEW_MATERIAL X6S
J 0
(-1450 1875);
DISPLAY 0.638298 (-1450 1875);
PAINT BROWN (-1450 1875);
DISPLAY BOTH (-1450 1875);
FORCEPROP 1 LAST PATH I232
J 0
(-1450 2375);
DISPLAY 0.978723 (-1450 2375);
PAINT WHITE (-1450 2375);
DISPLAY INVISIBLE (-1450 2375);
FORCEPROP 1 LAST MATERIAL X5R
J 0
(-1450 2125);
DISPLAY 0.617021 (-1450 2125);
PAINT SKYBLUE (-1450 2125);
DISPLAY INVISIBLE (-1450 2125);
FORCEPROP 2 LAST SEC 1
J 0
(-1450 2425);
DISPLAY 0.680851 (-1450 2425);
PAINT MONO (-1450 2425);
DISPLAY INVISIBLE (-1450 2425);
FORCEPROP 2 LAST SEC_TYPE 0805
J 0
(-1450 2425);
DISPLAY 1.021277 (-1450 2425);
PAINT ORANGE (-1450 2425);
DISPLAY INVISIBLE (-1450 2425);
FORCEPROP 2 LAST ROOM VDDQ_ABC_PWR_VR
J 0
(-1450 2375);
PAINT MONO (-1450 2375);
DISPLAY INVISIBLE (-1450 2375);
FORCEPROP 2 LAST BOM_COST MEM_VRD_PVDDQ_CD
J 0
(-1450 2375);
PAINT MONO (-1450 2375);
DISPLAY INVISIBLE (-1450 2375);
FORCEPROP 2 LAST CDS_LIB mstr_discrete
J 0
(-1500 2225);
PAINT MONO (-1500 2225);
DISPLAY INVISIBLE (-1500 2225);
FORCEPROP 0 LAST CDS_SEC 1
J 0
(-1450 2375);
PAINT MONO (-1450 2375);
DISPLAY INVISIBLE (-1450 2375);
FORCEPROP 2 LAST CDS_LOCATION C5P13
J 0
(-1450 2325);
DISPLAY 0.617021 (-1450 2325);
PAINT AQUA (-1450 2325);
DISPLAY INVISIBLE (-1450 2325);
FORCEADD CAP..1
(-1750 2225);
FORCEPROP 0 LAST NEW_PN 078.1071T.M002
J 0
(-1700 2075);
DISPLAY 0.638298 (-1700 2075);
PAINT BROWN (-1700 2075);
DISPLAY BOTH (-1700 2075);
FORCEPROP 1 LASTPIN (-1750 2325) $PN 1
J 0
(-1740 2305);
DISPLAY 0.617021 (-1740 2305);
PAINT ORANGE (-1740 2305);
FORCEPROP 1 LASTPIN (-1750 2125) $PN 2
J 0
(-1740 2130);
DISPLAY 0.617021 (-1740 2130);
PAINT ORANGE (-1740 2130);
FORCEPROP 1 LAST PACK_TYPE 0805
J 0
(-1650 2150);
DISPLAY 0.617021 (-1650 2150);
PAINT SKYBLUE (-1650 2150);
FORCEPROP 1 LAST VALUE 100UF
J 0
(-1650 2300);
DISPLAY 0.617021 (-1650 2300);
PAINT SKYBLUE (-1650 2300);
FORCEPROP 1 LAST PART_NUMBER 602433-112
R 1
J 0
(-1675 2150);
DISPLAY 0.617021 (-1675 2150);
PAINT BLUE (-1675 2150);
FORCEPROP 1 LAST VOLTAGE 4V
J 0
(-1650 2250);
DISPLAY 0.617021 (-1650 2250);
PAINT SKYBLUE (-1650 2250);
FORCEPROP 1 LAST TOLERANCE 20%
J 0
(-1650 2200);
DISPLAY 0.617021 (-1650 2200);
PAINT SKYBLUE (-1650 2200);
FORCEPROP 0 LAST NEW_MATERIAL X6S
J 0
(-1700 2025);
DISPLAY 0.638298 (-1700 2025);
PAINT BROWN (-1700 2025);
DISPLAY BOTH (-1700 2025);
FORCEPROP 1 LAST LOCATION C4P5
J 0
(-1650 2350);
DISPLAY 0.617021 (-1650 2350);
PAINT AQUA (-1650 2350);
FORCEPROP 0 LAST GROUP PWR_MCP_CAP
J 0
(-1700 1975);
DISPLAY 0.638298 (-1700 1975);
PAINT BROWN (-1700 1975);
DISPLAY BOTH (-1700 1975);
FORCEPROP 2 LAST CDS_LOCATION C4P5
J 0
(-1700 2325);
DISPLAY 0.617021 (-1700 2325);
PAINT AQUA (-1700 2325);
DISPLAY INVISIBLE (-1700 2325);
FORCEPROP 1 LAST MATERIAL X5R
J 0
(-1700 2125);
DISPLAY 0.617021 (-1700 2125);
PAINT SKYBLUE (-1700 2125);
DISPLAY INVISIBLE (-1700 2125);
FORCEPROP 2 LAST SEC 1
J 0
(-1700 2425);
DISPLAY 0.680851 (-1700 2425);
PAINT MONO (-1700 2425);
DISPLAY INVISIBLE (-1700 2425);
FORCEPROP 2 LAST SEC_TYPE 0805
J 0
(-1700 2425);
DISPLAY 1.021277 (-1700 2425);
PAINT ORANGE (-1700 2425);
DISPLAY INVISIBLE (-1700 2425);
FORCEPROP 2 LAST ROOM VDDQ_ABC_PWR_VR
J 0
(-1700 2375);
PAINT MONO (-1700 2375);
DISPLAY INVISIBLE (-1700 2375);
FORCEPROP 2 LAST BOM_COST MEM_VRD_PVDDQ_CD
J 0
(-1700 2375);
PAINT MONO (-1700 2375);
DISPLAY INVISIBLE (-1700 2375);
FORCEPROP 2 LAST CDS_LIB mstr_discrete
J 0
(-1750 2225);
PAINT MONO (-1750 2225);
DISPLAY INVISIBLE (-1750 2225);
FORCEPROP 0 LAST CDS_SEC 1
J 0
(-1700 2375);
PAINT MONO (-1700 2375);
DISPLAY INVISIBLE (-1700 2375);
FORCEPROP 1 LAST PATH I233
J 0
(-1700 2375);
DISPLAY 0.978723 (-1700 2375);
PAINT WHITE (-1700 2375);
DISPLAY INVISIBLE (-1700 2375);
FORCEADD CAP..1
(-1250 2225);
FORCEPROP 0 LAST NEW_PN 078.1071T.M002
J 0
(-1200 2075);
DISPLAY 0.638298 (-1200 2075);
PAINT BROWN (-1200 2075);
DISPLAY BOTH (-1200 2075);
FORCEPROP 1 LASTPIN (-1250 2125) $PN 2
J 0
(-1240 2130);
DISPLAY 0.617021 (-1240 2130);
PAINT ORANGE (-1240 2130);
FORCEPROP 1 LAST TOLERANCE 20%
J 0
(-1150 2200);
DISPLAY 0.617021 (-1150 2200);
PAINT SKYBLUE (-1150 2200);
FORCEPROP 0 LAST NEW_MATERIAL X6S
J 0
(-1200 2025);
DISPLAY 0.638298 (-1200 2025);
PAINT BROWN (-1200 2025);
DISPLAY BOTH (-1200 2025);
FORCEPROP 1 LAST LOCATION C5P20
J 0
(-1150 2350);
DISPLAY 0.617021 (-1150 2350);
PAINT AQUA (-1150 2350);
FORCEPROP 1 LASTPIN (-1250 2325) $PN 1
J 0
(-1240 2305);
DISPLAY 0.617021 (-1240 2305);
PAINT ORANGE (-1240 2305);
FORCEPROP 1 LAST PART_NUMBER 602433-112
R 1
J 0
(-1175 2150);
DISPLAY 0.617021 (-1175 2150);
PAINT BLUE (-1175 2150);
FORCEPROP 1 LAST VOLTAGE 4V
J 0
(-1150 2250);
DISPLAY 0.617021 (-1150 2250);
PAINT SKYBLUE (-1150 2250);
FORCEPROP 1 LAST VALUE 100UF
J 0
(-1150 2300);
DISPLAY 0.617021 (-1150 2300);
PAINT SKYBLUE (-1150 2300);
FORCEPROP 1 LAST PACK_TYPE 0805
J 0
(-1150 2150);
DISPLAY 0.617021 (-1150 2150);
PAINT SKYBLUE (-1150 2150);
FORCEPROP 0 LAST GROUP PWR_MCP_CAP
J 0
(-1200 1975);
DISPLAY 0.638298 (-1200 1975);
PAINT BROWN (-1200 1975);
DISPLAY BOTH (-1200 1975);
FORCEPROP 1 LAST MATERIAL X5R
J 0
(-1200 2125);
DISPLAY 0.617021 (-1200 2125);
PAINT SKYBLUE (-1200 2125);
DISPLAY INVISIBLE (-1200 2125);
FORCEPROP 2 LAST SEC 1
J 0
(-1200 2425);
DISPLAY 0.680851 (-1200 2425);
PAINT MONO (-1200 2425);
DISPLAY INVISIBLE (-1200 2425);
FORCEPROP 2 LAST SEC_TYPE 0805
J 0
(-1200 2425);
DISPLAY 1.021277 (-1200 2425);
PAINT ORANGE (-1200 2425);
DISPLAY INVISIBLE (-1200 2425);
FORCEPROP 2 LAST ROOM VDDQ_ABC_PWR_VR
J 0
(-1200 2375);
PAINT MONO (-1200 2375);
DISPLAY INVISIBLE (-1200 2375);
FORCEPROP 2 LAST BOM_COST MEM_VRD_PVDDQ_CD
J 0
(-1200 2375);
PAINT MONO (-1200 2375);
DISPLAY INVISIBLE (-1200 2375);
FORCEPROP 2 LAST CDS_LIB mstr_discrete
J 0
(-1250 2225);
PAINT MONO (-1250 2225);
DISPLAY INVISIBLE (-1250 2225);
FORCEPROP 0 LAST CDS_SEC 1
J 0
(-1200 2375);
PAINT MONO (-1200 2375);
DISPLAY INVISIBLE (-1200 2375);
FORCEPROP 1 LAST PATH I234
J 0
(-1200 2375);
DISPLAY 0.978723 (-1200 2375);
PAINT WHITE (-1200 2375);
DISPLAY INVISIBLE (-1200 2375);
FORCEPROP 2 LAST CDS_LOCATION C5P20
J 0
(-1200 2325);
DISPLAY 0.617021 (-1200 2325);
PAINT AQUA (-1200 2325);
DISPLAY INVISIBLE (-1200 2325);
FORCEADD CAP..1
(-1000 2225);
FORCEPROP 0 LAST NEW_MATERIAL X6S
J 0
(-950 1825);
DISPLAY 0.638298 (-950 1825);
PAINT BROWN (-950 1825);
DISPLAY BOTH (-950 1825);
FORCEPROP 1 LASTPIN (-1000 2125) $PN 2
J 0
(-990 2130);
DISPLAY 0.617021 (-990 2130);
PAINT ORANGE (-990 2130);
FORCEPROP 1 LAST PACK_TYPE 0805
J 0
(-900 2150);
DISPLAY 0.617021 (-900 2150);
PAINT SKYBLUE (-900 2150);
FORCEPROP 1 LAST TOLERANCE 20%
J 0
(-900 2200);
DISPLAY 0.617021 (-900 2200);
PAINT SKYBLUE (-900 2200);
FORCEPROP 1 LASTPIN (-1000 2325) $PN 1
J 0
(-990 2305);
DISPLAY 0.617021 (-990 2305);
PAINT ORANGE (-990 2305);
FORCEPROP 1 LAST VOLTAGE 4V
J 0
(-900 2250);
DISPLAY 0.617021 (-900 2250);
PAINT SKYBLUE (-900 2250);
FORCEPROP 1 LAST PART_NUMBER 602433-112
R 1
J 0
(-925 2150);
DISPLAY 0.617021 (-925 2150);
PAINT BLUE (-925 2150);
FORCEPROP 1 LAST LOCATION C5P21
J 0
(-900 2350);
DISPLAY 0.617021 (-900 2350);
PAINT AQUA (-900 2350);
FORCEPROP 1 LAST VALUE 100UF
J 0
(-900 2300);
DISPLAY 0.617021 (-900 2300);
PAINT SKYBLUE (-900 2300);
FORCEPROP 0 LAST GROUP PWR_MCP_CAP
J 0
(-950 1775);
DISPLAY 0.638298 (-950 1775);
PAINT BROWN (-950 1775);
DISPLAY BOTH (-950 1775);
FORCEPROP 0 LAST NEW_PN 078.1071T.M002
J 0
(-950 1875);
DISPLAY 0.638298 (-950 1875);
PAINT BROWN (-950 1875);
DISPLAY BOTH (-950 1875);
FORCEPROP 2 LAST CDS_LOCATION C5P21
J 0
(-950 2325);
DISPLAY 0.617021 (-950 2325);
PAINT AQUA (-950 2325);
DISPLAY INVISIBLE (-950 2325);
FORCEPROP 0 LAST CDS_SEC 1
J 0
(-950 2375);
PAINT MONO (-950 2375);
DISPLAY INVISIBLE (-950 2375);
FORCEPROP 2 LAST CDS_LIB mstr_discrete
J 0
(-1000 2225);
PAINT MONO (-1000 2225);
DISPLAY INVISIBLE (-1000 2225);
FORCEPROP 2 LAST BOM_COST MEM_VRD_PVDDQ_CD
J 0
(-950 2375);
PAINT MONO (-950 2375);
DISPLAY INVISIBLE (-950 2375);
FORCEPROP 2 LAST ROOM VDDQ_ABC_PWR_VR
J 0
(-950 2375);
PAINT MONO (-950 2375);
DISPLAY INVISIBLE (-950 2375);
FORCEPROP 2 LAST SEC_TYPE 0805
J 0
(-950 2425);
DISPLAY 1.021277 (-950 2425);
PAINT ORANGE (-950 2425);
DISPLAY INVISIBLE (-950 2425);
FORCEPROP 2 LAST SEC 1
J 0
(-950 2425);
DISPLAY 0.680851 (-950 2425);
PAINT MONO (-950 2425);
DISPLAY INVISIBLE (-950 2425);
FORCEPROP 1 LAST MATERIAL X5R
J 0
(-950 2125);
DISPLAY 0.617021 (-950 2125);
PAINT SKYBLUE (-950 2125);
DISPLAY INVISIBLE (-950 2125);
FORCEPROP 1 LAST PATH I235
J 0
(-950 2375);
DISPLAY 0.978723 (-950 2375);
PAINT WHITE (-950 2375);
DISPLAY INVISIBLE (-950 2375);
FORCEADD CAP..1
(-750 2225);
FORCEPROP 1 LASTPIN (-750 2325) $PN 1
J 0
(-740 2305);
DISPLAY 0.617021 (-740 2305);
PAINT ORANGE (-740 2305);
FORCEPROP 1 LASTPIN (-750 2125) $PN 2
J 0
(-740 2130);
DISPLAY 0.617021 (-740 2130);
PAINT ORANGE (-740 2130);
FORCEPROP 1 LAST PACK_TYPE 0805
J 0
(-700 2150);
DISPLAY 0.617021 (-700 2150);
PAINT SKYBLUE (-700 2150);
FORCEPROP 1 LAST LOCATION C5P12
J 0
(-700 2400);
DISPLAY 0.617021 (-700 2400);
PAINT AQUA (-700 2400);
FORCEPROP 1 LAST VALUE 100UF
J 0
(-700 2350);
DISPLAY 0.617021 (-700 2350);
PAINT SKYBLUE (-700 2350);
FORCEPROP 1 LAST VOLTAGE 4V
J 0
(-700 2300);
DISPLAY 0.617021 (-700 2300);
PAINT SKYBLUE (-700 2300);
FORCEPROP 1 LAST TOLERANCE 20%
J 0
(-700 2250);
DISPLAY 0.617021 (-700 2250);
PAINT SKYBLUE (-700 2250);
FORCEPROP 0 LAST NEW_MATERIAL X6S
J 0
(-725 2025);
DISPLAY 0.638298 (-725 2025);
PAINT BROWN (-725 2025);
DISPLAY BOTH (-725 2025);
FORCEPROP 0 LAST GROUP PWR_MCP_CAP
J 0
(-725 1975);
DISPLAY 0.638298 (-725 1975);
PAINT BROWN (-725 1975);
DISPLAY BOTH (-725 1975);
FORCEPROP 1 LAST PART_NUMBER 602433-112
J 0
(-700 2200);
DISPLAY 0.617021 (-700 2200);
PAINT BLUE (-700 2200);
FORCEPROP 0 LAST NEW_PN 078.1071T.M002
J 0
(-725 2075);
DISPLAY 0.638298 (-725 2075);
PAINT BROWN (-725 2075);
DISPLAY BOTH (-725 2075);
FORCEPROP 2 LAST CDS_LOCATION C5P12
J 0
(-700 2325);
DISPLAY 0.617021 (-700 2325);
PAINT AQUA (-700 2325);
DISPLAY INVISIBLE (-700 2325);
FORCEPROP 1 LAST MATERIAL X5R
J 0
(-700 2125);
DISPLAY 0.617021 (-700 2125);
PAINT SKYBLUE (-700 2125);
DISPLAY INVISIBLE (-700 2125);
FORCEPROP 2 LAST SEC 1
J 0
(-700 2425);
DISPLAY 0.680851 (-700 2425);
PAINT MONO (-700 2425);
DISPLAY INVISIBLE (-700 2425);
FORCEPROP 2 LAST SEC_TYPE 0805
J 0
(-700 2425);
DISPLAY 1.021277 (-700 2425);
PAINT ORANGE (-700 2425);
DISPLAY INVISIBLE (-700 2425);
FORCEPROP 2 LAST ROOM VDDQ_ABC_PWR_VR
J 0
(-700 2375);
PAINT MONO (-700 2375);
DISPLAY INVISIBLE (-700 2375);
FORCEPROP 2 LAST BOM_COST MEM_VRD_PVDDQ_CD
J 0
(-700 2375);
PAINT MONO (-700 2375);
DISPLAY INVISIBLE (-700 2375);
FORCEPROP 2 LAST CDS_LIB mstr_discrete
J 0
(-750 2225);
PAINT MONO (-750 2225);
DISPLAY INVISIBLE (-750 2225);
FORCEPROP 0 LAST CDS_SEC 1
J 0
(-700 2375);
PAINT MONO (-700 2375);
DISPLAY INVISIBLE (-700 2375);
FORCEPROP 1 LAST PATH I236
J 0
(-700 2375);
DISPLAY 0.978723 (-700 2375);
PAINT WHITE (-700 2375);
DISPLAY INVISIBLE (-700 2375);
FORCEADD GND..1
(-1800 3575);
FORCEPROP 3 LASTPIN (-1800 3625) SIG_NAME GND\g
J 0
(-1790 3635);
DISPLAY 0.659574 (-1790 3635);
PAINT MONO (-1790 3635);
DISPLAY INVISIBLE (-1790 3635);
FORCEPROP 1 LAST HDL_POWER GND
J 0
(-1800 3725);
DISPLAY 0.893617 (-1800 3725);
PAINT GREEN (-1800 3725);
DISPLAY INVISIBLE (-1800 3725);
FORCEPROP 1 LAST BODY_TYPE PLUMBING
J 0
(-1845 3532);
DISPLAY 0.340426 (-1845 3532);
PAINT GREEN (-1845 3532);
DISPLAY INVISIBLE (-1845 3532);
FORCEPROP 2 LAST CDS_LIB mstr_symbols
J 0
(-1800 3575);
PAINT ORANGE (-1800 3575);
DISPLAY INVISIBLE (-1800 3575);
FORCEPROP 1 LAST SIZE 1B
J 0
(-1725 3525);
DISPLAY 0.893617 (-1725 3525);
PAINT GREEN (-1725 3525);
DISPLAY INVISIBLE (-1725 3525);
FORCEPROP 1 LAST VOLTAGE 0
J 0
(-1800 3575);
PAINT SKYBLUE (-1800 3575);
DISPLAY INVISIBLE (-1800 3575);
FORCEPROP 1 LAST PATH I237
J 0
(-1725 3575);
DISPLAY 0.872340 (-1725 3575);
PAINT AQUA (-1725 3575);
DISPLAY INVISIBLE (-1725 3575);
FORCEADD PVSA_CPU0..1
(-4450 1250);
FORCEPROP 3 LASTPIN (-4450 1200) SIG_NAME PVSA_CPU0\g
J 0
(-4440 1210);
DISPLAY 0.659574 (-4440 1210);
PAINT MONO (-4440 1210);
DISPLAY INVISIBLE (-4440 1210);
FORCEPROP 1 LAST HDL_POWER PVSA_CPU0
J 1
(-4450 1300);
DISPLAY 0.872340 (-4450 1300);
PAINT GREEN (-4450 1300);
DISPLAY INVISIBLE (-4450 1300);
FORCEPROP 1 LAST PATH I24
J 0
(-4400 1275);
DISPLAY 0.872340 (-4400 1275);
PAINT AQUA (-4400 1275);
DISPLAY INVISIBLE (-4400 1275);
FORCEPROP 1 LAST BODY_TYPE PLUMBING
J 0
(-4495 1207);
DISPLAY 0.340426 (-4495 1207);
PAINT GREEN (-4495 1207);
DISPLAY INVISIBLE (-4495 1207);
FORCEPROP 2 LAST CDS_LIB mstr_symbols
J 0
(-4450 1250);
PAINT ORANGE (-4450 1250);
DISPLAY INVISIBLE (-4450 1250);
FORCEPROP 1 LAST VOLTAGE 1.1V
J 0
(-4495 1207);
DISPLAY 0.340426 (-4495 1207);
PAINT SKYBLUE (-4495 1207);
DISPLAY INVISIBLE (-4495 1207);
FORCEADD CAP..1
(-4450 950);
FORCEPROP 1 LAST PART_NUMBER C95333-002
J 0
(-4400 850);
DISPLAY 0.617021 (-4400 850);
PAINT BLUE (-4400 850);
FORCEPROP 1 LAST MATERIAL X6S
J 0
(-4400 900);
DISPLAY 0.638298 (-4400 900);
PAINT SKYBLUE (-4400 900);
FORCEPROP 1 LAST PACK_TYPE 0805LF
J 0
(-4400 800);
DISPLAY 0.617021 (-4400 800);
PAINT SKYBLUE (-4400 800);
FORCEPROP 1 LAST VALUE 22UF
J 0
(-4400 1050);
DISPLAY 0.617021 (-4400 1050);
PAINT SKYBLUE (-4400 1050);
FORCEPROP 1 LAST VOLTAGE 4V
J 0
(-4400 1000);
DISPLAY 0.638298 (-4400 1000);
PAINT SKYBLUE (-4400 1000);
FORCEPROP 1 LASTPIN (-4450 1050) $PN 1
J 0
(-4440 1030);
DISPLAY 0.617021 (-4440 1030);
PAINT GREEN (-4440 1030);
FORCEPROP 1 LASTPIN (-4450 850) $PN 2
J 0
(-4440 830);
DISPLAY 0.617021 (-4440 830);
PAINT GREEN (-4440 830);
FORCEPROP 1 LAST TOLERANCE 20%
J 0
(-4400 950);
DISPLAY 0.617021 (-4400 950);
PAINT SKYBLUE (-4400 950);
FORCEPROP 1 LAST LOCATION C5P7
J 0
(-4400 1100);
DISPLAY 0.617021 (-4400 1100);
PAINT AQUA (-4400 1100);
FORCEPROP 0 LAST GROUP PWR_MLCC_CAP
J 0
(-4394 762);
DISPLAY 0.638298 (-4394 762);
PAINT BROWN (-4394 762);
DISPLAY BOTH (-4394 762);
FORCEPROP 2 LAST CDS_LIB mstr_discrete
J 0
(-4450 950);
PAINT ORANGE (-4450 950);
DISPLAY INVISIBLE (-4450 950);
FORCEPROP 2 LAST BOM_COST PROC_SOCKET
J 0
(-4400 1150);
DISPLAY 1.021277 (-4400 1150);
PAINT ORANGE (-4400 1150);
DISPLAY INVISIBLE (-4400 1150);
FORCEPROP 2 LAST CDS_SEC 1
J 0
(-4400 1150);
DISPLAY 1.021277 (-4400 1150);
PAINT ORANGE (-4400 1150);
DISPLAY INVISIBLE (-4400 1150);
FORCEPROP 2 LAST $SEC 1
J 0
(-4400 1150);
DISPLAY 0.680851 (-4400 1150);
PAINT MONO (-4400 1150);
DISPLAY INVISIBLE (-4400 1150);
FORCEPROP 2 LAST CDS_LOCATION C5P7
J 0
(-4400 1050);
DISPLAY 0.617021 (-4400 1050);
PAINT AQUA (-4400 1050);
DISPLAY INVISIBLE (-4400 1050);
FORCEPROP 1 LAST PATH I25
J 0
(-4400 1100);
DISPLAY 0.978723 (-4400 1100);
PAINT WHITE (-4400 1100);
DISPLAY INVISIBLE (-4400 1100);
FORCEPROP 2 LAST ROOM PVCCIN_CPU0_DECAP_VR
J 0
(-4400 1100);
DISPLAY 1.021277 (-4400 1100);
PAINT ORANGE (-4400 1100);
DISPLAY INVISIBLE (-4400 1100);
FORCEADD CAP..1
(-5350 2250);
FORCEPROP 1 LAST VOLTAGE 4V
J 0
(-5300 2300);
DISPLAY 0.638298 (-5300 2300);
PAINT SKYBLUE (-5300 2300);
FORCEPROP 1 LAST LOCATION C5P23
J 0
(-5300 2400);
DISPLAY 0.617021 (-5300 2400);
PAINT AQUA (-5300 2400);
FORCEPROP 1 LASTPIN (-5350 2350) $PN 1
J 0
(-5340 2330);
DISPLAY 0.617021 (-5340 2330);
PAINT GREEN (-5340 2330);
FORCEPROP 1 LASTPIN (-5350 2150) $PN 2
J 0
(-5340 2130);
DISPLAY 0.617021 (-5340 2130);
PAINT GREEN (-5340 2130);
FORCEPROP 1 LAST PART_NUMBER C95333-006
R 1
J 0
(-5400 2150);
DISPLAY 0.617021 (-5400 2150);
PAINT BLUE (-5400 2150);
FORCEPROP 1 LAST TOLERANCE 20%
J 0
(-5300 2250);
DISPLAY 0.617021 (-5300 2250);
PAINT SKYBLUE (-5300 2250);
FORCEPROP 1 LAST MATERIAL X6S
J 0
(-5300 2200);
DISPLAY 0.638298 (-5300 2200);
PAINT SKYBLUE (-5300 2200);
FORCEPROP 1 LAST VALUE 47UF
J 0
(-5300 2350);
DISPLAY 0.617021 (-5300 2350);
PAINT SKYBLUE (-5300 2350);
FORCEPROP 0 LAST GROUP PWR_MLCC_CAP
J 0
(-5295 2102);
DISPLAY 0.638298 (-5295 2102);
PAINT BROWN (-5295 2102);
DISPLAY BOTH (-5295 2102);
FORCEPROP 1 LAST PACK_TYPE 0805
J 0
(-5300 2150);
DISPLAY 0.617021 (-5300 2150);
PAINT SKYBLUE (-5300 2150);
FORCEPROP 2 LAST ROOM PVCCIN_CPU0_DECAP_VR
J 0
(-5300 2400);
DISPLAY 1.021277 (-5300 2400);
PAINT ORANGE (-5300 2400);
DISPLAY INVISIBLE (-5300 2400);
FORCEPROP 1 LAST PATH I28
J 0
(-5300 2400);
DISPLAY 0.978723 (-5300 2400);
PAINT WHITE (-5300 2400);
DISPLAY INVISIBLE (-5300 2400);
FORCEPROP 2 LAST CDS_LOCATION C5P23
J 0
(-5300 2350);
DISPLAY 0.617021 (-5300 2350);
PAINT AQUA (-5300 2350);
DISPLAY INVISIBLE (-5300 2350);
FORCEPROP 2 LAST $SEC 1
J 0
(-5300 2450);
DISPLAY 0.680851 (-5300 2450);
PAINT MONO (-5300 2450);
DISPLAY INVISIBLE (-5300 2450);
FORCEPROP 2 LAST CDS_SEC 1
J 0
(-5300 2450);
DISPLAY 1.021277 (-5300 2450);
PAINT ORANGE (-5300 2450);
DISPLAY INVISIBLE (-5300 2450);
FORCEPROP 2 LAST BOM_COST PROC_SOCKET
J 0
(-5300 2450);
DISPLAY 1.021277 (-5300 2450);
PAINT ORANGE (-5300 2450);
DISPLAY INVISIBLE (-5300 2450);
FORCEPROP 2 LAST CDS_LIB mstr_discrete
J 0
(-5350 2250);
PAINT ORANGE (-5350 2250);
DISPLAY INVISIBLE (-5350 2250);
FORCEADD GND..1
(-5050 1275);
FORCEPROP 3 LASTPIN (-5050 1325) SIG_NAME GND\g
J 0
(-5040 1335);
DISPLAY 0.659574 (-5040 1335);
PAINT MONO (-5040 1335);
DISPLAY INVISIBLE (-5040 1335);
FORCEPROP 1 LAST VOLTAGE 0
J 0
(-5050 1275);
PAINT SKYBLUE (-5050 1275);
DISPLAY INVISIBLE (-5050 1275);
FORCEPROP 2 LAST CDS_LIB mstr_symbols
J 0
(-5050 1275);
PAINT ORANGE (-5050 1275);
DISPLAY INVISIBLE (-5050 1275);
FORCEPROP 1 LAST SIZE 1B
J 0
(-4975 1225);
DISPLAY 0.893617 (-4975 1225);
PAINT GREEN (-4975 1225);
DISPLAY INVISIBLE (-4975 1225);
FORCEPROP 1 LAST BODY_TYPE PLUMBING
J 0
(-5095 1232);
DISPLAY 0.340426 (-5095 1232);
PAINT GREEN (-5095 1232);
DISPLAY INVISIBLE (-5095 1232);
FORCEPROP 1 LAST PATH I32
J 0
(-4975 1275);
DISPLAY 0.872340 (-4975 1275);
PAINT AQUA (-4975 1275);
DISPLAY INVISIBLE (-4975 1275);
FORCEPROP 1 LAST HDL_POWER GND
J 0
(-5050 1425);
DISPLAY 0.893617 (-5050 1425);
PAINT GREEN (-5050 1425);
DISPLAY INVISIBLE (-5050 1425);
FORCEADD CAP..1
(-5050 1550);
FORCEPROP 1 LAST VOLTAGE 4V
J 0
(-5000 1550);
DISPLAY 0.638298 (-5000 1550);
PAINT SKYBLUE (-5000 1550);
FORCEPROP 1 LAST VALUE 47UF
J 0
(-5000 1600);
DISPLAY 0.617021 (-5000 1600);
PAINT SKYBLUE (-5000 1600);
FORCEPROP 1 LAST TOLERANCE 20%
J 0
(-5000 1500);
DISPLAY 0.617021 (-5000 1500);
PAINT SKYBLUE (-5000 1500);
FORCEPROP 1 LAST MATERIAL X6S
J 0
(-5000 1450);
DISPLAY 0.638298 (-5000 1450);
PAINT SKYBLUE (-5000 1450);
FORCEPROP 1 LAST PACK_TYPE 0805
J 0
(-5000 1400);
DISPLAY 0.617021 (-5000 1400);
PAINT SKYBLUE (-5000 1400);
FORCEPROP 1 LASTPIN (-5050 1450) $PN 2
J 0
(-5040 1430);
DISPLAY 0.617021 (-5040 1430);
PAINT GREEN (-5040 1430);
FORCEPROP 1 LAST PART_NUMBER C95333-006
R 1
J 0
(-5100 1375);
DISPLAY 0.617021 (-5100 1375);
PAINT BLUE (-5100 1375);
FORCEPROP 1 LASTPIN (-5050 1650) $PN 1
J 0
(-5040 1630);
DISPLAY 0.617021 (-5040 1630);
PAINT GREEN (-5040 1630);
FORCEPROP 0 LAST GROUP PWR_MLCC_CAP
J 0
(-4995 1352);
DISPLAY 0.638298 (-4995 1352);
PAINT BROWN (-4995 1352);
DISPLAY BOTH (-4995 1352);
FORCEPROP 1 LAST LOCATION C5P24
J 0
(-5000 1650);
DISPLAY 0.617021 (-5000 1650);
PAINT AQUA (-5000 1650);
FORCEPROP 2 LAST ROOM PVCCIN_CPU0_DECAP_VR
J 0
(-5000 1700);
DISPLAY 1.021277 (-5000 1700);
PAINT ORANGE (-5000 1700);
DISPLAY INVISIBLE (-5000 1700);
FORCEPROP 1 LAST PATH I33
J 0
(-5000 1700);
DISPLAY 0.978723 (-5000 1700);
PAINT WHITE (-5000 1700);
DISPLAY INVISIBLE (-5000 1700);
FORCEPROP 2 LAST CDS_LOCATION C5P24
J 0
(-5000 1650);
DISPLAY 0.617021 (-5000 1650);
PAINT AQUA (-5000 1650);
DISPLAY INVISIBLE (-5000 1650);
FORCEPROP 2 LAST $SEC 1
J 0
(-5000 1750);
DISPLAY 0.680851 (-5000 1750);
PAINT MONO (-5000 1750);
DISPLAY INVISIBLE (-5000 1750);
FORCEPROP 2 LAST CDS_SEC 1
J 0
(-5000 1750);
DISPLAY 1.021277 (-5000 1750);
PAINT ORANGE (-5000 1750);
DISPLAY INVISIBLE (-5000 1750);
FORCEPROP 2 LAST BOM_COST PROC_SOCKET
J 0
(-5000 1750);
DISPLAY 1.021277 (-5000 1750);
PAINT ORANGE (-5000 1750);
DISPLAY INVISIBLE (-5000 1750);
FORCEPROP 2 LAST CDS_LIB mstr_discrete
J 0
(-5050 1550);
PAINT ORANGE (-5050 1550);
DISPLAY INVISIBLE (-5050 1550);
FORCEADD GND..1
(-5350 575);
FORCEPROP 3 LASTPIN (-5350 625) SIG_NAME GND\g
J 0
(-5340 635);
DISPLAY 0.659574 (-5340 635);
PAINT MONO (-5340 635);
DISPLAY INVISIBLE (-5340 635);
FORCEPROP 1 LAST HDL_POWER GND
J 0
(-5350 725);
DISPLAY 0.893617 (-5350 725);
PAINT GREEN (-5350 725);
DISPLAY INVISIBLE (-5350 725);
FORCEPROP 1 LAST PATH I35
J 0
(-5275 575);
DISPLAY 0.872340 (-5275 575);
PAINT AQUA (-5275 575);
DISPLAY INVISIBLE (-5275 575);
FORCEPROP 1 LAST BODY_TYPE PLUMBING
J 0
(-5395 532);
DISPLAY 0.340426 (-5395 532);
PAINT GREEN (-5395 532);
DISPLAY INVISIBLE (-5395 532);
FORCEPROP 2 LAST CDS_LIB mstr_symbols
J 0
(-5350 575);
PAINT ORANGE (-5350 575);
DISPLAY INVISIBLE (-5350 575);
FORCEPROP 1 LAST SIZE 1B
J 0
(-5275 525);
DISPLAY 0.893617 (-5275 525);
PAINT GREEN (-5275 525);
DISPLAY INVISIBLE (-5275 525);
FORCEPROP 1 LAST VOLTAGE 0
J 0
(-5350 575);
PAINT SKYBLUE (-5350 575);
DISPLAY INVISIBLE (-5350 575);
FORCEADD CAP..1
(-5350 850);
FORCEPROP 0 LAST GROUP PWR_MLCC_CAP
J 0
(-5295 702);
DISPLAY 0.638298 (-5295 702);
PAINT BROWN (-5295 702);
DISPLAY BOTH (-5295 702);
FORCEPROP 1 LAST PART_NUMBER C95333-006
R 1
J 0
(-5400 750);
DISPLAY 0.617021 (-5400 750);
PAINT BLUE (-5400 750);
FORCEPROP 1 LAST VALUE 47UF
J 0
(-5300 950);
DISPLAY 0.617021 (-5300 950);
PAINT SKYBLUE (-5300 950);
FORCEPROP 1 LASTPIN (-5350 950) $PN 1
J 0
(-5340 930);
DISPLAY 0.617021 (-5340 930);
PAINT GREEN (-5340 930);
FORCEPROP 1 LAST LOCATION C5P25
J 0
(-5300 1000);
DISPLAY 0.617021 (-5300 1000);
PAINT AQUA (-5300 1000);
FORCEPROP 1 LAST VOLTAGE 4V
J 0
(-5300 900);
DISPLAY 0.638298 (-5300 900);
PAINT SKYBLUE (-5300 900);
FORCEPROP 1 LAST PACK_TYPE 0805
J 0
(-5300 750);
DISPLAY 0.617021 (-5300 750);
PAINT SKYBLUE (-5300 750);
FORCEPROP 1 LASTPIN (-5350 750) $PN 2
J 0
(-5340 730);
DISPLAY 0.617021 (-5340 730);
PAINT GREEN (-5340 730);
FORCEPROP 1 LAST MATERIAL X6S
J 0
(-5300 800);
DISPLAY 0.638298 (-5300 800);
PAINT SKYBLUE (-5300 800);
FORCEPROP 1 LAST TOLERANCE 20%
J 0
(-5300 850);
DISPLAY 0.617021 (-5300 850);
PAINT SKYBLUE (-5300 850);
FORCEPROP 2 LAST BOM_COST PROC_SOCKET
J 0
(-5300 1050);
DISPLAY 1.021277 (-5300 1050);
PAINT ORANGE (-5300 1050);
DISPLAY INVISIBLE (-5300 1050);
FORCEPROP 2 LAST CDS_LIB mstr_discrete
J 0
(-5350 850);
PAINT ORANGE (-5350 850);
DISPLAY INVISIBLE (-5350 850);
FORCEPROP 2 LAST CDS_SEC 1
J 0
(-5300 1050);
DISPLAY 1.021277 (-5300 1050);
PAINT ORANGE (-5300 1050);
DISPLAY INVISIBLE (-5300 1050);
FORCEPROP 2 LAST $SEC 1
J 0
(-5300 1050);
DISPLAY 0.680851 (-5300 1050);
PAINT MONO (-5300 1050);
DISPLAY INVISIBLE (-5300 1050);
FORCEPROP 2 LAST CDS_LOCATION C5P25
J 0
(-5300 950);
DISPLAY 0.617021 (-5300 950);
PAINT AQUA (-5300 950);
DISPLAY INVISIBLE (-5300 950);
FORCEPROP 1 LAST PATH I37
J 0
(-5300 1000);
DISPLAY 0.978723 (-5300 1000);
PAINT WHITE (-5300 1000);
DISPLAY INVISIBLE (-5300 1000);
FORCEPROP 2 LAST ROOM PVCCIN_CPU0_DECAP_VR
J 0
(-5300 1000);
DISPLAY 1.021277 (-5300 1000);
PAINT ORANGE (-5300 1000);
DISPLAY INVISIBLE (-5300 1000);
FORCEADD CAP..1
(-6550 2250);
FORCEPROP 1 LAST PACK_TYPE 0805
J 0
(-6500 2150);
DISPLAY 0.617021 (-6500 2150);
PAINT SKYBLUE (-6500 2150);
FORCEPROP 1 LASTPIN (-6550 2350) $PN 1
J 0
(-6540 2330);
DISPLAY 0.617021 (-6540 2330);
PAINT GREEN (-6540 2330);
FORCEPROP 1 LASTPIN (-6550 2150) $PN 2
J 0
(-6540 2130);
DISPLAY 0.617021 (-6540 2130);
PAINT GREEN (-6540 2130);
FORCEPROP 1 LAST MATERIAL X6S
J 0
(-6500 2200);
DISPLAY 0.638298 (-6500 2200);
PAINT SKYBLUE (-6500 2200);
FORCEPROP 1 LAST VOLTAGE 4V
J 0
(-6500 2250);
DISPLAY 0.638298 (-6500 2250);
PAINT SKYBLUE (-6500 2250);
FORCEPROP 1 LAST VALUE 47UF
J 0
(-6500 2350);
DISPLAY 0.617021 (-6500 2350);
PAINT SKYBLUE (-6500 2350);
FORCEPROP 1 LAST LOCATION C5P14
J 0
(-6500 2400);
DISPLAY 0.617021 (-6500 2400);
PAINT AQUA (-6500 2400);
FORCEPROP 0 LAST GROUP PWR_MLCC_CAP
J 0
(-6495 2102);
DISPLAY 0.638298 (-6495 2102);
PAINT BROWN (-6495 2102);
DISPLAY BOTH (-6495 2102);
FORCEPROP 1 LAST TOLERANCE 20%
J 0
(-6500 2300);
DISPLAY 0.617021 (-6500 2300);
PAINT SKYBLUE (-6500 2300);
FORCEPROP 1 LAST PART_NUMBER C95333-006
R 1
J 0
(-6600 2150);
DISPLAY 0.617021 (-6600 2150);
PAINT BLUE (-6600 2150);
FORCEPROP 2 LAST ROOM PVCCIN_CPU0_DECAP_VR
J 0
(-6500 2400);
DISPLAY 1.021277 (-6500 2400);
PAINT ORANGE (-6500 2400);
DISPLAY INVISIBLE (-6500 2400);
FORCEPROP 1 LAST PATH I41
J 0
(-6500 2400);
DISPLAY 0.978723 (-6500 2400);
PAINT WHITE (-6500 2400);
DISPLAY INVISIBLE (-6500 2400);
FORCEPROP 2 LAST CDS_LOCATION C5P14
J 0
(-6500 2350);
DISPLAY 0.617021 (-6500 2350);
PAINT AQUA (-6500 2350);
DISPLAY INVISIBLE (-6500 2350);
FORCEPROP 2 LAST $SEC 1
J 0
(-6500 2450);
PAINT MONO (-6500 2450);
DISPLAY INVISIBLE (-6500 2450);
FORCEPROP 2 LAST CDS_SEC 1
J 0
(-6500 2450);
PAINT MONO (-6500 2450);
DISPLAY INVISIBLE (-6500 2450);
FORCEPROP 2 LAST CDS_LIB mstr_discrete
J 0
(-6550 2250);
PAINT ORANGE (-6550 2250);
DISPLAY INVISIBLE (-6550 2250);
FORCEPROP 2 LAST BOM_COST PROC_SOCKET
J 0
(-6500 2450);
DISPLAY 1.021277 (-6500 2450);
PAINT ORANGE (-6500 2450);
DISPLAY INVISIBLE (-6500 2450);
FORCEADD PVCCIN_CPU0..1
(-5950 1850);
FORCEPROP 3 LASTPIN (-5950 1800) SIG_NAME PVCCIN_CPU0\g
J 0
(-5940 1810);
DISPLAY 0.659574 (-5940 1810);
PAINT MONO (-5940 1810);
DISPLAY INVISIBLE (-5940 1810);
FORCEPROP 1 LAST HDL_POWER PVCCIN_CPU0
J 1
(-5950 1900);
DISPLAY 0.872340 (-5950 1900);
PAINT GREEN (-5950 1900);
DISPLAY INVISIBLE (-5950 1900);
FORCEPROP 1 LAST BODY_TYPE PLUMBING
J 0
(-5995 1807);
DISPLAY 0.340426 (-5995 1807);
PAINT GREEN (-5995 1807);
DISPLAY INVISIBLE (-5995 1807);
FORCEPROP 2 LAST CDS_LIB mstr_symbols
J 0
(-5950 1850);
PAINT ORANGE (-5950 1850);
DISPLAY INVISIBLE (-5950 1850);
FORCEPROP 1 LAST VOLTAGE 2.0V
J 0
(-5995 1807);
DISPLAY 0.340426 (-5995 1807);
PAINT SKYBLUE (-5995 1807);
DISPLAY INVISIBLE (-5995 1807);
FORCEPROP 1 LAST PATH I43
J 0
(-5900 1875);
DISPLAY 0.872340 (-5900 1875);
PAINT AQUA (-5900 1875);
DISPLAY INVISIBLE (-5900 1875);
FORCEADD CAP..1
(-5950 1550);
FORCEPROP 1 LAST PART_NUMBER C95333-006
R 1
J 0
(-6000 1450);
DISPLAY 0.617021 (-6000 1450);
PAINT BLUE (-6000 1450);
FORCEPROP 1 LAST VOLTAGE 4V
J 0
(-5900 1600);
DISPLAY 0.638298 (-5900 1600);
PAINT SKYBLUE (-5900 1600);
FORCEPROP 1 LASTPIN (-5950 1650) $PN 1
J 0
(-5940 1630);
DISPLAY 0.617021 (-5940 1630);
PAINT GREEN (-5940 1630);
FORCEPROP 1 LAST VALUE 47UF
J 0
(-5900 1650);
DISPLAY 0.617021 (-5900 1650);
PAINT SKYBLUE (-5900 1650);
FORCEPROP 1 LASTPIN (-5950 1450) $PN 2
J 0
(-5940 1430);
DISPLAY 0.617021 (-5940 1430);
PAINT GREEN (-5940 1430);
FORCEPROP 1 LAST LOCATION C5P27
J 0
(-5900 1700);
DISPLAY 0.617021 (-5900 1700);
PAINT AQUA (-5900 1700);
FORCEPROP 0 LAST GROUP PWR_MLCC_CAP
J 0
(-5895 1402);
DISPLAY 0.638298 (-5895 1402);
PAINT BROWN (-5895 1402);
DISPLAY BOTH (-5895 1402);
FORCEPROP 1 LAST PACK_TYPE 0805
J 0
(-5900 1450);
DISPLAY 0.617021 (-5900 1450);
PAINT SKYBLUE (-5900 1450);
FORCEPROP 1 LAST MATERIAL X6S
J 0
(-5900 1500);
DISPLAY 0.638298 (-5900 1500);
PAINT SKYBLUE (-5900 1500);
FORCEPROP 1 LAST TOLERANCE 20%
J 0
(-5900 1550);
DISPLAY 0.617021 (-5900 1550);
PAINT SKYBLUE (-5900 1550);
FORCEPROP 2 LAST ROOM PVCCIN_CPU0_DECAP_VR
J 0
(-5900 1700);
DISPLAY 1.021277 (-5900 1700);
PAINT ORANGE (-5900 1700);
DISPLAY INVISIBLE (-5900 1700);
FORCEPROP 1 LAST PATH I44
J 0
(-5900 1700);
DISPLAY 0.978723 (-5900 1700);
PAINT WHITE (-5900 1700);
DISPLAY INVISIBLE (-5900 1700);
FORCEPROP 2 LAST CDS_LOCATION C5P27
J 0
(-5900 1650);
DISPLAY 0.617021 (-5900 1650);
PAINT AQUA (-5900 1650);
DISPLAY INVISIBLE (-5900 1650);
FORCEPROP 2 LAST $SEC 1
J 0
(-5900 1750);
DISPLAY 0.680851 (-5900 1750);
PAINT MONO (-5900 1750);
DISPLAY INVISIBLE (-5900 1750);
FORCEPROP 2 LAST CDS_SEC 1
J 0
(-5900 1750);
DISPLAY 1.021277 (-5900 1750);
PAINT ORANGE (-5900 1750);
DISPLAY INVISIBLE (-5900 1750);
FORCEPROP 2 LAST BOM_COST PROC_SOCKET
J 0
(-5900 1750);
DISPLAY 1.021277 (-5900 1750);
PAINT ORANGE (-5900 1750);
DISPLAY INVISIBLE (-5900 1750);
FORCEPROP 2 LAST CDS_LIB mstr_discrete
J 0
(-5950 1550);
PAINT ORANGE (-5950 1550);
DISPLAY INVISIBLE (-5950 1550);
FORCEADD PVCCIN_CPU0..1
(-5950 1150);
FORCEPROP 3 LASTPIN (-5950 1100) SIG_NAME PVCCIN_CPU0\g
J 0
(-5940 1110);
DISPLAY 0.659574 (-5940 1110);
PAINT MONO (-5940 1110);
DISPLAY INVISIBLE (-5940 1110);
FORCEPROP 1 LAST HDL_POWER PVCCIN_CPU0
J 1
(-5950 1200);
DISPLAY 0.872340 (-5950 1200);
PAINT GREEN (-5950 1200);
DISPLAY INVISIBLE (-5950 1200);
FORCEPROP 1 LAST PATH I45
J 0
(-5900 1175);
DISPLAY 0.872340 (-5900 1175);
PAINT AQUA (-5900 1175);
DISPLAY INVISIBLE (-5900 1175);
FORCEPROP 1 LAST BODY_TYPE PLUMBING
J 0
(-5995 1107);
DISPLAY 0.340426 (-5995 1107);
PAINT GREEN (-5995 1107);
DISPLAY INVISIBLE (-5995 1107);
FORCEPROP 2 LAST CDS_LIB mstr_symbols
J 0
(-5950 1150);
PAINT ORANGE (-5950 1150);
DISPLAY INVISIBLE (-5950 1150);
FORCEPROP 1 LAST VOLTAGE 2.0V
J 0
(-5995 1107);
DISPLAY 0.340426 (-5995 1107);
PAINT SKYBLUE (-5995 1107);
DISPLAY INVISIBLE (-5995 1107);
FORCEADD GND..1
(-7750 1975);
FORCEPROP 3 LASTPIN (-7750 2025) SIG_NAME GND\g
J 0
(-7740 2035);
DISPLAY 0.659574 (-7740 2035);
PAINT MONO (-7740 2035);
DISPLAY INVISIBLE (-7740 2035);
FORCEPROP 1 LAST VOLTAGE 0
J 0
(-7750 1975);
PAINT SKYBLUE (-7750 1975);
DISPLAY INVISIBLE (-7750 1975);
FORCEPROP 2 LAST CDS_LIB mstr_symbols
J 0
(-7750 1975);
PAINT ORANGE (-7750 1975);
DISPLAY INVISIBLE (-7750 1975);
FORCEPROP 1 LAST SIZE 1B
J 0
(-7675 1925);
DISPLAY 0.893617 (-7675 1925);
PAINT GREEN (-7675 1925);
DISPLAY INVISIBLE (-7675 1925);
FORCEPROP 1 LAST BODY_TYPE PLUMBING
J 0
(-7795 1932);
DISPLAY 0.340426 (-7795 1932);
PAINT GREEN (-7795 1932);
DISPLAY INVISIBLE (-7795 1932);
FORCEPROP 1 LAST PATH I46
J 0
(-7675 1975);
DISPLAY 0.872340 (-7675 1975);
PAINT AQUA (-7675 1975);
DISPLAY INVISIBLE (-7675 1975);
FORCEPROP 1 LAST HDL_POWER GND
J 0
(-7750 2125);
DISPLAY 0.893617 (-7750 2125);
PAINT GREEN (-7750 2125);
DISPLAY INVISIBLE (-7750 2125);
FORCEADD GND..1
(-7750 1275);
FORCEPROP 3 LASTPIN (-7750 1325) SIG_NAME GND\g
J 0
(-7740 1335);
DISPLAY 0.659574 (-7740 1335);
PAINT MONO (-7740 1335);
DISPLAY INVISIBLE (-7740 1335);
FORCEPROP 1 LAST VOLTAGE 0
J 0
(-7750 1275);
PAINT SKYBLUE (-7750 1275);
DISPLAY INVISIBLE (-7750 1275);
FORCEPROP 2 LAST CDS_LIB mstr_symbols
J 0
(-7750 1275);
PAINT ORANGE (-7750 1275);
DISPLAY INVISIBLE (-7750 1275);
FORCEPROP 1 LAST SIZE 1B
J 0
(-7675 1225);
DISPLAY 0.893617 (-7675 1225);
PAINT GREEN (-7675 1225);
DISPLAY INVISIBLE (-7675 1225);
FORCEPROP 1 LAST BODY_TYPE PLUMBING
J 0
(-7795 1232);
DISPLAY 0.340426 (-7795 1232);
PAINT GREEN (-7795 1232);
DISPLAY INVISIBLE (-7795 1232);
FORCEPROP 1 LAST PATH I48
J 0
(-7675 1275);
DISPLAY 0.872340 (-7675 1275);
PAINT AQUA (-7675 1275);
DISPLAY INVISIBLE (-7675 1275);
FORCEPROP 1 LAST HDL_POWER GND
J 0
(-7750 1425);
DISPLAY 0.893617 (-7750 1425);
PAINT GREEN (-7750 1425);
DISPLAY INVISIBLE (-7750 1425);
FORCEADD GND..1
(-750 1925);
FORCEPROP 3 LASTPIN (-750 1975) SIG_NAME GND\g
J 0
(-740 1985);
DISPLAY 0.659574 (-740 1985);
PAINT MONO (-740 1985);
DISPLAY INVISIBLE (-740 1985);
FORCEPROP 1 LAST PATH I5
J 0
(-675 1925);
DISPLAY 0.872340 (-675 1925);
PAINT AQUA (-675 1925);
DISPLAY INVISIBLE (-675 1925);
FORCEPROP 1 LAST VOLTAGE 0
J 0
(-750 1925);
PAINT SKYBLUE (-750 1925);
DISPLAY INVISIBLE (-750 1925);
FORCEPROP 2 LAST CDS_LIB mstr_symbols
J 0
(-750 1925);
PAINT ORANGE (-750 1925);
DISPLAY INVISIBLE (-750 1925);
FORCEPROP 1 LAST SIZE 1B
J 0
(-675 1875);
DISPLAY 0.893617 (-675 1875);
PAINT GREEN (-675 1875);
DISPLAY INVISIBLE (-675 1875);
FORCEPROP 1 LAST BODY_TYPE PLUMBING
J 0
(-795 1882);
DISPLAY 0.340426 (-795 1882);
PAINT GREEN (-795 1882);
DISPLAY INVISIBLE (-795 1882);
FORCEPROP 1 LAST HDL_POWER GND
J 0
(-750 2075);
DISPLAY 0.893617 (-750 2075);
PAINT GREEN (-750 2075);
DISPLAY INVISIBLE (-750 2075);
FORCEADD CAP..1
(-7150 2250);
FORCEPROP 0 LAST GROUP PWR_MLCC_CAP
J 0
(-7095 2102);
DISPLAY 0.638298 (-7095 2102);
PAINT BROWN (-7095 2102);
DISPLAY BOTH (-7095 2102);
FORCEPROP 1 LAST PACK_TYPE 0805
J 0
(-7100 2150);
DISPLAY 0.617021 (-7100 2150);
PAINT SKYBLUE (-7100 2150);
FORCEPROP 1 LASTPIN (-7150 2150) $PN 2
J 0
(-7140 2130);
DISPLAY 0.617021 (-7140 2130);
PAINT GREEN (-7140 2130);
FORCEPROP 1 LAST MATERIAL X6S
J 0
(-7100 2200);
DISPLAY 0.638298 (-7100 2200);
PAINT SKYBLUE (-7100 2200);
FORCEPROP 1 LAST VOLTAGE 4V
J 0
(-7100 2250);
DISPLAY 0.638298 (-7100 2250);
PAINT SKYBLUE (-7100 2250);
FORCEPROP 1 LASTPIN (-7150 2350) $PN 1
J 0
(-7140 2330);
DISPLAY 0.617021 (-7140 2330);
PAINT GREEN (-7140 2330);
FORCEPROP 1 LAST VALUE 47UF
J 0
(-7100 2350);
DISPLAY 0.617021 (-7100 2350);
PAINT SKYBLUE (-7100 2350);
FORCEPROP 1 LAST LOCATION C5P33
J 0
(-7100 2400);
DISPLAY 0.617021 (-7100 2400);
PAINT AQUA (-7100 2400);
FORCEPROP 1 LAST PART_NUMBER C95333-006
R 1
J 0
(-7200 2150);
DISPLAY 0.617021 (-7200 2150);
PAINT BLUE (-7200 2150);
FORCEPROP 1 LAST TOLERANCE 20%
J 0
(-7100 2300);
DISPLAY 0.617021 (-7100 2300);
PAINT SKYBLUE (-7100 2300);
FORCEPROP 2 LAST ROOM PVCCIN_CPU0_DECAP_VR
J 0
(-7100 2400);
DISPLAY 1.021277 (-7100 2400);
PAINT ORANGE (-7100 2400);
DISPLAY INVISIBLE (-7100 2400);
FORCEPROP 1 LAST PATH I50
J 0
(-7100 2400);
DISPLAY 0.978723 (-7100 2400);
PAINT WHITE (-7100 2400);
DISPLAY INVISIBLE (-7100 2400);
FORCEPROP 2 LAST CDS_LOCATION C5P33
J 0
(-7100 2350);
DISPLAY 0.617021 (-7100 2350);
PAINT AQUA (-7100 2350);
DISPLAY INVISIBLE (-7100 2350);
FORCEPROP 2 LAST $SEC 1
J 0
(-7100 2450);
PAINT MONO (-7100 2450);
DISPLAY INVISIBLE (-7100 2450);
FORCEPROP 2 LAST CDS_SEC 1
J 0
(-7100 2450);
PAINT MONO (-7100 2450);
DISPLAY INVISIBLE (-7100 2450);
FORCEPROP 2 LAST CDS_LIB mstr_discrete
J 0
(-7150 2250);
PAINT ORANGE (-7150 2250);
DISPLAY INVISIBLE (-7150 2250);
FORCEPROP 2 LAST BOM_COST PROC_SOCKET
J 0
(-7100 2450);
DISPLAY 1.021277 (-7100 2450);
PAINT ORANGE (-7100 2450);
DISPLAY INVISIBLE (-7100 2450);
FORCEADD CAP..1
(-7450 2250);
FORCEPROP 0 LAST GROUP PWR_MLCC_CAP
J 0
(-7395 2052);
DISPLAY 0.638298 (-7395 2052);
PAINT BROWN (-7395 2052);
DISPLAY BOTH (-7395 2052);
FORCEPROP 1 LAST VOLTAGE 4V
J 0
(-7400 2250);
DISPLAY 0.638298 (-7400 2250);
PAINT SKYBLUE (-7400 2250);
FORCEPROP 1 LAST PACK_TYPE 0805
J 0
(-7400 2150);
DISPLAY 0.617021 (-7400 2150);
PAINT SKYBLUE (-7400 2150);
FORCEPROP 1 LAST MATERIAL X6S
J 0
(-7400 2200);
DISPLAY 0.638298 (-7400 2200);
PAINT SKYBLUE (-7400 2200);
FORCEPROP 1 LASTPIN (-7450 2150) $PN 2
J 0
(-7440 2130);
DISPLAY 0.617021 (-7440 2130);
PAINT GREEN (-7440 2130);
FORCEPROP 1 LAST LOCATION C5P35
J 0
(-7400 2400);
DISPLAY 0.617021 (-7400 2400);
PAINT AQUA (-7400 2400);
FORCEPROP 1 LAST VALUE 47UF
J 0
(-7400 2350);
DISPLAY 0.617021 (-7400 2350);
PAINT SKYBLUE (-7400 2350);
FORCEPROP 1 LAST PART_NUMBER C95333-006
R 1
J 0
(-7500 2150);
DISPLAY 0.617021 (-7500 2150);
PAINT BLUE (-7500 2150);
FORCEPROP 1 LASTPIN (-7450 2350) $PN 1
J 0
(-7440 2330);
DISPLAY 0.617021 (-7440 2330);
PAINT GREEN (-7440 2330);
FORCEPROP 1 LAST TOLERANCE 20%
J 0
(-7400 2300);
DISPLAY 0.617021 (-7400 2300);
PAINT SKYBLUE (-7400 2300);
FORCEPROP 2 LAST BOM_COST PROC_SOCKET
J 0
(-7400 2450);
DISPLAY 1.021277 (-7400 2450);
PAINT ORANGE (-7400 2450);
DISPLAY INVISIBLE (-7400 2450);
FORCEPROP 2 LAST CDS_LIB mstr_discrete
J 0
(-7450 2250);
PAINT ORANGE (-7450 2250);
DISPLAY INVISIBLE (-7450 2250);
FORCEPROP 2 LAST CDS_SEC 1
J 0
(-7400 2450);
PAINT MONO (-7400 2450);
DISPLAY INVISIBLE (-7400 2450);
FORCEPROP 2 LAST $SEC 1
J 0
(-7400 2450);
PAINT MONO (-7400 2450);
DISPLAY INVISIBLE (-7400 2450);
FORCEPROP 2 LAST CDS_LOCATION C5P35
J 0
(-7400 2350);
DISPLAY 0.617021 (-7400 2350);
PAINT AQUA (-7400 2350);
DISPLAY INVISIBLE (-7400 2350);
FORCEPROP 1 LAST PATH I51
J 0
(-7400 2400);
DISPLAY 0.978723 (-7400 2400);
PAINT WHITE (-7400 2400);
DISPLAY INVISIBLE (-7400 2400);
FORCEPROP 2 LAST ROOM PVCCIN_CPU0_DECAP_VR
J 0
(-7400 2400);
DISPLAY 1.021277 (-7400 2400);
PAINT ORANGE (-7400 2400);
DISPLAY INVISIBLE (-7400 2400);
FORCEADD CAP..1
(-7150 1550);
FORCEPROP 0 LAST GROUP PWR_MLCC_CAP
J 0
(-7095 1402);
DISPLAY 0.638298 (-7095 1402);
PAINT BROWN (-7095 1402);
DISPLAY BOTH (-7095 1402);
FORCEPROP 1 LAST PART_NUMBER C95333-006
R 1
J 0
(-7200 1450);
DISPLAY 0.617021 (-7200 1450);
PAINT BLUE (-7200 1450);
FORCEPROP 1 LAST PACK_TYPE 0805
J 0
(-7100 1450);
DISPLAY 0.617021 (-7100 1450);
PAINT SKYBLUE (-7100 1450);
FORCEPROP 1 LAST LOCATION C5P32
J 0
(-7100 1700);
DISPLAY 0.617021 (-7100 1700);
PAINT AQUA (-7100 1700);
FORCEPROP 1 LAST VALUE 47UF
J 0
(-7100 1650);
DISPLAY 0.617021 (-7100 1650);
PAINT SKYBLUE (-7100 1650);
FORCEPROP 1 LASTPIN (-7150 1650) $PN 1
J 0
(-7140 1630);
DISPLAY 0.617021 (-7140 1630);
PAINT GREEN (-7140 1630);
FORCEPROP 1 LAST VOLTAGE 4V
J 0
(-7100 1600);
DISPLAY 0.638298 (-7100 1600);
PAINT SKYBLUE (-7100 1600);
FORCEPROP 1 LASTPIN (-7150 1450) $PN 2
J 0
(-7140 1430);
DISPLAY 0.617021 (-7140 1430);
PAINT GREEN (-7140 1430);
FORCEPROP 1 LAST MATERIAL X6S
J 0
(-7100 1500);
DISPLAY 0.638298 (-7100 1500);
PAINT SKYBLUE (-7100 1500);
FORCEPROP 1 LAST TOLERANCE 20%
J 0
(-7100 1550);
DISPLAY 0.617021 (-7100 1550);
PAINT SKYBLUE (-7100 1550);
FORCEPROP 2 LAST ROOM PVCCIN_CPU0_DECAP_VR
J 0
(-7100 1700);
DISPLAY 1.021277 (-7100 1700);
PAINT ORANGE (-7100 1700);
DISPLAY INVISIBLE (-7100 1700);
FORCEPROP 1 LAST PATH I53
J 0
(-7100 1700);
DISPLAY 0.978723 (-7100 1700);
PAINT WHITE (-7100 1700);
DISPLAY INVISIBLE (-7100 1700);
FORCEPROP 2 LAST CDS_LOCATION C5P32
J 0
(-7100 1650);
DISPLAY 0.617021 (-7100 1650);
PAINT AQUA (-7100 1650);
DISPLAY INVISIBLE (-7100 1650);
FORCEPROP 2 LAST $SEC 1
J 0
(-7100 1750);
DISPLAY 0.680851 (-7100 1750);
PAINT MONO (-7100 1750);
DISPLAY INVISIBLE (-7100 1750);
FORCEPROP 2 LAST CDS_SEC 1
J 0
(-7100 1750);
DISPLAY 1.021277 (-7100 1750);
PAINT ORANGE (-7100 1750);
DISPLAY INVISIBLE (-7100 1750);
FORCEPROP 2 LAST CDS_LIB mstr_discrete
J 0
(-7150 1550);
PAINT ORANGE (-7150 1550);
DISPLAY INVISIBLE (-7150 1550);
FORCEPROP 2 LAST BOM_COST PROC_SOCKET
J 0
(-7100 1750);
DISPLAY 1.021277 (-7100 1750);
PAINT ORANGE (-7100 1750);
DISPLAY INVISIBLE (-7100 1750);
FORCEADD CAP..1
(-7450 1550);
FORCEPROP 0 LAST GROUP PWR_MLCC_CAP
J 0
(-7395 1352);
DISPLAY 0.638298 (-7395 1352);
PAINT BROWN (-7395 1352);
DISPLAY BOTH (-7395 1352);
FORCEPROP 1 LAST PACK_TYPE 0805
J 0
(-7400 1450);
DISPLAY 0.617021 (-7400 1450);
PAINT SKYBLUE (-7400 1450);
FORCEPROP 1 LAST MATERIAL X6S
J 0
(-7400 1500);
DISPLAY 0.638298 (-7400 1500);
PAINT SKYBLUE (-7400 1500);
FORCEPROP 1 LAST TOLERANCE 20%
J 0
(-7400 1550);
DISPLAY 0.617021 (-7400 1550);
PAINT SKYBLUE (-7400 1550);
FORCEPROP 1 LAST VOLTAGE 4V
J 0
(-7400 1600);
DISPLAY 0.638298 (-7400 1600);
PAINT SKYBLUE (-7400 1600);
FORCEPROP 1 LAST VALUE 47UF
J 0
(-7400 1650);
DISPLAY 0.617021 (-7400 1650);
PAINT SKYBLUE (-7400 1650);
FORCEPROP 1 LAST LOCATION C5P34
J 0
(-7400 1700);
DISPLAY 0.617021 (-7400 1700);
PAINT AQUA (-7400 1700);
FORCEPROP 1 LASTPIN (-7450 1450) $PN 2
J 0
(-7440 1430);
DISPLAY 0.617021 (-7440 1430);
PAINT GREEN (-7440 1430);
FORCEPROP 1 LAST PART_NUMBER C95333-006
R 1
J 0
(-7500 1450);
DISPLAY 0.617021 (-7500 1450);
PAINT BLUE (-7500 1450);
FORCEPROP 1 LASTPIN (-7450 1650) $PN 1
J 0
(-7440 1630);
DISPLAY 0.617021 (-7440 1630);
PAINT GREEN (-7440 1630);
FORCEPROP 2 LAST BOM_COST PROC_SOCKET
J 0
(-7400 1750);
DISPLAY 1.021277 (-7400 1750);
PAINT ORANGE (-7400 1750);
DISPLAY INVISIBLE (-7400 1750);
FORCEPROP 2 LAST CDS_LIB mstr_discrete
J 0
(-7450 1550);
PAINT ORANGE (-7450 1550);
DISPLAY INVISIBLE (-7450 1550);
FORCEPROP 2 LAST CDS_SEC 1
J 0
(-7400 1750);
DISPLAY 1.021277 (-7400 1750);
PAINT ORANGE (-7400 1750);
DISPLAY INVISIBLE (-7400 1750);
FORCEPROP 2 LAST $SEC 1
J 0
(-7400 1750);
DISPLAY 0.680851 (-7400 1750);
PAINT MONO (-7400 1750);
DISPLAY INVISIBLE (-7400 1750);
FORCEPROP 2 LAST CDS_LOCATION C5P34
J 0
(-7400 1650);
DISPLAY 0.617021 (-7400 1650);
PAINT AQUA (-7400 1650);
DISPLAY INVISIBLE (-7400 1650);
FORCEPROP 1 LAST PATH I54
J 0
(-7400 1700);
DISPLAY 0.978723 (-7400 1700);
PAINT WHITE (-7400 1700);
DISPLAY INVISIBLE (-7400 1700);
FORCEPROP 2 LAST ROOM PVCCIN_CPU0_DECAP_VR
J 0
(-7400 1700);
DISPLAY 1.021277 (-7400 1700);
PAINT ORANGE (-7400 1700);
DISPLAY INVISIBLE (-7400 1700);
FORCEADD CAP..1
(-5650 850);
FORCEPROP 0 LAST GROUP PWR_MLCC_CAP
J 0
(-5595 652);
DISPLAY 0.638298 (-5595 652);
PAINT BROWN (-5595 652);
DISPLAY BOTH (-5595 652);
FORCEPROP 1 LAST PART_NUMBER C95333-006
R 1
J 0
(-5700 750);
DISPLAY 0.617021 (-5700 750);
PAINT BLUE (-5700 750);
FORCEPROP 1 LAST VALUE 47UF
J 0
(-5600 950);
DISPLAY 0.617021 (-5600 950);
PAINT SKYBLUE (-5600 950);
FORCEPROP 1 LAST VOLTAGE 4V
J 0
(-5600 900);
DISPLAY 0.638298 (-5600 900);
PAINT SKYBLUE (-5600 900);
FORCEPROP 1 LAST MATERIAL X6S
J 0
(-5600 800);
DISPLAY 0.638298 (-5600 800);
PAINT SKYBLUE (-5600 800);
FORCEPROP 1 LASTPIN (-5650 950) $PN 1
J 0
(-5640 930);
DISPLAY 0.617021 (-5640 930);
PAINT GREEN (-5640 930);
FORCEPROP 1 LAST TOLERANCE 20%
J 0
(-5600 850);
DISPLAY 0.617021 (-5600 850);
PAINT SKYBLUE (-5600 850);
FORCEPROP 1 LAST LOCATION C5P22
J 0
(-5600 1000);
DISPLAY 0.617021 (-5600 1000);
PAINT AQUA (-5600 1000);
FORCEPROP 1 LASTPIN (-5650 750) $PN 2
J 0
(-5640 730);
DISPLAY 0.617021 (-5640 730);
PAINT GREEN (-5640 730);
FORCEPROP 1 LAST PACK_TYPE 0805
J 0
(-5600 750);
DISPLAY 0.617021 (-5600 750);
PAINT SKYBLUE (-5600 750);
FORCEPROP 2 LAST BOM_COST PROC_SOCKET
J 0
(-5600 1050);
DISPLAY 1.021277 (-5600 1050);
PAINT ORANGE (-5600 1050);
DISPLAY INVISIBLE (-5600 1050);
FORCEPROP 2 LAST CDS_LIB mstr_discrete
J 0
(-5650 850);
PAINT ORANGE (-5650 850);
DISPLAY INVISIBLE (-5650 850);
FORCEPROP 2 LAST CDS_SEC 1
J 0
(-5600 1050);
DISPLAY 1.021277 (-5600 1050);
PAINT ORANGE (-5600 1050);
DISPLAY INVISIBLE (-5600 1050);
FORCEPROP 2 LAST $SEC 1
J 0
(-5600 1050);
DISPLAY 0.680851 (-5600 1050);
PAINT MONO (-5600 1050);
DISPLAY INVISIBLE (-5600 1050);
FORCEPROP 2 LAST CDS_LOCATION C5P22
J 0
(-5600 950);
DISPLAY 0.617021 (-5600 950);
PAINT AQUA (-5600 950);
DISPLAY INVISIBLE (-5600 950);
FORCEPROP 1 LAST PATH I55
J 0
(-5600 1000);
DISPLAY 0.978723 (-5600 1000);
PAINT WHITE (-5600 1000);
DISPLAY INVISIBLE (-5600 1000);
FORCEPROP 2 LAST ROOM PVCCIN_CPU0_DECAP_VR
J 0
(-5600 1000);
DISPLAY 1.021277 (-5600 1000);
PAINT ORANGE (-5600 1000);
DISPLAY INVISIBLE (-5600 1000);
FORCEADD CAP..1
(-5950 850);
FORCEPROP 1 LAST LOCATION C5P26
J 0
(-5900 1000);
DISPLAY 0.617021 (-5900 1000);
PAINT AQUA (-5900 1000);
FORCEPROP 1 LAST VALUE 47UF
J 0
(-5900 950);
DISPLAY 0.617021 (-5900 950);
PAINT SKYBLUE (-5900 950);
FORCEPROP 1 LAST PART_NUMBER C95333-006
R 1
J 0
(-6000 750);
DISPLAY 0.617021 (-6000 750);
PAINT BLUE (-6000 750);
FORCEPROP 1 LAST MATERIAL X6S
J 0
(-5900 800);
DISPLAY 0.638298 (-5900 800);
PAINT SKYBLUE (-5900 800);
FORCEPROP 1 LAST VOLTAGE 4V
J 0
(-5900 900);
DISPLAY 0.638298 (-5900 900);
PAINT SKYBLUE (-5900 900);
FORCEPROP 1 LASTPIN (-5950 950) $PN 1
J 0
(-5940 930);
DISPLAY 0.617021 (-5940 930);
PAINT GREEN (-5940 930);
FORCEPROP 1 LAST TOLERANCE 20%
J 0
(-5900 850);
DISPLAY 0.617021 (-5900 850);
PAINT SKYBLUE (-5900 850);
FORCEPROP 1 LAST PACK_TYPE 0805
J 0
(-5900 750);
DISPLAY 0.617021 (-5900 750);
PAINT SKYBLUE (-5900 750);
FORCEPROP 1 LASTPIN (-5950 750) $PN 2
J 0
(-5940 730);
DISPLAY 0.617021 (-5940 730);
PAINT GREEN (-5940 730);
FORCEPROP 0 LAST GROUP PWR_MLCC_CAP
J 0
(-5895 702);
DISPLAY 0.638298 (-5895 702);
PAINT BROWN (-5895 702);
DISPLAY BOTH (-5895 702);
FORCEPROP 2 LAST ROOM PVCCIN_CPU0_DECAP_VR
J 0
(-5900 1000);
DISPLAY 1.021277 (-5900 1000);
PAINT ORANGE (-5900 1000);
DISPLAY INVISIBLE (-5900 1000);
FORCEPROP 1 LAST PATH I56
J 0
(-5900 1000);
DISPLAY 0.978723 (-5900 1000);
PAINT WHITE (-5900 1000);
DISPLAY INVISIBLE (-5900 1000);
FORCEPROP 2 LAST CDS_LOCATION C5P26
J 0
(-5900 950);
DISPLAY 0.617021 (-5900 950);
PAINT AQUA (-5900 950);
DISPLAY INVISIBLE (-5900 950);
FORCEPROP 2 LAST $SEC 1
J 0
(-5900 1050);
DISPLAY 0.680851 (-5900 1050);
PAINT MONO (-5900 1050);
DISPLAY INVISIBLE (-5900 1050);
FORCEPROP 2 LAST CDS_SEC 1
J 0
(-5900 1050);
DISPLAY 1.021277 (-5900 1050);
PAINT ORANGE (-5900 1050);
DISPLAY INVISIBLE (-5900 1050);
FORCEPROP 2 LAST CDS_LIB mstr_discrete
J 0
(-5950 850);
PAINT ORANGE (-5950 850);
DISPLAY INVISIBLE (-5950 850);
FORCEPROP 2 LAST BOM_COST PROC_SOCKET
J 0
(-5900 1050);
DISPLAY 1.021277 (-5900 1050);
PAINT ORANGE (-5900 1050);
DISPLAY INVISIBLE (-5900 1050);
FORCEADD CAP..1
(-6550 850);
FORCEPROP 1 LAST PACK_TYPE 0805
J 0
(-6505 750);
DISPLAY 0.617021 (-6505 750);
PAINT SKYBLUE (-6505 750);
FORCEPROP 1 LAST PART_NUMBER C95333-006
R 1
J 0
(-6600 750);
DISPLAY 0.617021 (-6600 750);
PAINT BLUE (-6600 750);
FORCEPROP 1 LAST VOLTAGE 4V
J 0
(-6500 900);
DISPLAY 0.638298 (-6500 900);
PAINT SKYBLUE (-6500 900);
FORCEPROP 1 LAST TOLERANCE 20%
J 0
(-6500 850);
DISPLAY 0.617021 (-6500 850);
PAINT SKYBLUE (-6500 850);
FORCEPROP 1 LAST MATERIAL X6S
J 0
(-6500 800);
DISPLAY 0.638298 (-6500 800);
PAINT SKYBLUE (-6500 800);
FORCEPROP 1 LASTPIN (-6550 750) $PN 2
J 0
(-6540 730);
DISPLAY 0.617021 (-6540 730);
PAINT GREEN (-6540 730);
FORCEPROP 1 LASTPIN (-6550 950) $PN 1
J 0
(-6540 930);
DISPLAY 0.617021 (-6540 930);
PAINT GREEN (-6540 930);
FORCEPROP 1 LAST VALUE 47UF
J 0
(-6500 950);
DISPLAY 0.617021 (-6500 950);
PAINT SKYBLUE (-6500 950);
FORCEPROP 1 LAST LOCATION C5P40
J 0
(-6500 1000);
DISPLAY 0.617021 (-6500 1000);
PAINT AQUA (-6500 1000);
FORCEPROP 0 LAST GROUP PWR_MLCC_CAP
J 0
(-6495 702);
DISPLAY 0.638298 (-6495 702);
PAINT BROWN (-6495 702);
DISPLAY BOTH (-6495 702);
FORCEPROP 2 LAST ROOM PVCCIN_CPU0_DECAP_VR
J 0
(-6500 1000);
DISPLAY 1.021277 (-6500 1000);
PAINT ORANGE (-6500 1000);
DISPLAY INVISIBLE (-6500 1000);
FORCEPROP 1 LAST PATH I57
J 0
(-6500 1000);
DISPLAY 0.978723 (-6500 1000);
PAINT WHITE (-6500 1000);
DISPLAY INVISIBLE (-6500 1000);
FORCEPROP 2 LAST CDS_LOCATION C5P40
J 0
(-6500 950);
DISPLAY 0.617021 (-6500 950);
PAINT AQUA (-6500 950);
DISPLAY INVISIBLE (-6500 950);
FORCEPROP 2 LAST $SEC 1
J 0
(-6500 1050);
DISPLAY 0.680851 (-6500 1050);
PAINT MONO (-6500 1050);
DISPLAY INVISIBLE (-6500 1050);
FORCEPROP 2 LAST CDS_SEC 1
J 0
(-6500 1050);
DISPLAY 1.021277 (-6500 1050);
PAINT ORANGE (-6500 1050);
DISPLAY INVISIBLE (-6500 1050);
FORCEPROP 2 LAST CDS_LIB mstr_discrete
J 0
(-6550 850);
PAINT ORANGE (-6550 850);
DISPLAY INVISIBLE (-6550 850);
FORCEPROP 2 LAST BOM_COST PROC_SOCKET
J 0
(-6500 1050);
DISPLAY 1.021277 (-6500 1050);
PAINT ORANGE (-6500 1050);
DISPLAY INVISIBLE (-6500 1050);
FORCEADD GND..1
(-6550 575);
FORCEPROP 3 LASTPIN (-6550 625) SIG_NAME GND\g
J 0
(-6540 635);
DISPLAY 0.659574 (-6540 635);
PAINT MONO (-6540 635);
DISPLAY INVISIBLE (-6540 635);
FORCEPROP 1 LAST PATH I58
J 0
(-6475 575);
DISPLAY 0.872340 (-6475 575);
PAINT AQUA (-6475 575);
DISPLAY INVISIBLE (-6475 575);
FORCEPROP 1 LAST HDL_POWER GND
J 0
(-6550 725);
DISPLAY 0.893617 (-6550 725);
PAINT GREEN (-6550 725);
DISPLAY INVISIBLE (-6550 725);
FORCEPROP 1 LAST BODY_TYPE PLUMBING
J 0
(-6595 532);
DISPLAY 0.340426 (-6595 532);
PAINT GREEN (-6595 532);
DISPLAY INVISIBLE (-6595 532);
FORCEPROP 2 LAST CDS_LIB mstr_symbols
J 0
(-6550 575);
PAINT ORANGE (-6550 575);
DISPLAY INVISIBLE (-6550 575);
FORCEPROP 1 LAST SIZE 1B
J 0
(-6475 525);
DISPLAY 0.893617 (-6475 525);
PAINT GREEN (-6475 525);
DISPLAY INVISIBLE (-6475 525);
FORCEPROP 1 LAST VOLTAGE 0
J 0
(-6550 575);
PAINT SKYBLUE (-6550 575);
DISPLAY INVISIBLE (-6550 575);
FORCEADD PVCCIN_CPU0..1
(-7750 2550);
FORCEPROP 3 LASTPIN (-7750 2500) SIG_NAME PVCCIN_CPU0\g
J 0
(-7740 2510);
DISPLAY 0.659574 (-7740 2510);
PAINT MONO (-7740 2510);
DISPLAY INVISIBLE (-7740 2510);
FORCEPROP 1 LAST HDL_POWER PVCCIN_CPU0
J 1
(-7750 2600);
DISPLAY 0.872340 (-7750 2600);
PAINT GREEN (-7750 2600);
DISPLAY INVISIBLE (-7750 2600);
FORCEPROP 1 LAST PATH I62
J 0
(-7700 2575);
DISPLAY 0.872340 (-7700 2575);
PAINT AQUA (-7700 2575);
DISPLAY INVISIBLE (-7700 2575);
FORCEPROP 1 LAST BODY_TYPE PLUMBING
J 0
(-7795 2507);
DISPLAY 0.340426 (-7795 2507);
PAINT GREEN (-7795 2507);
DISPLAY INVISIBLE (-7795 2507);
FORCEPROP 2 LAST CDS_LIB mstr_symbols
J 0
(-7750 2550);
PAINT ORANGE (-7750 2550);
DISPLAY INVISIBLE (-7750 2550);
FORCEPROP 1 LAST VOLTAGE 2.0V
J 0
(-7795 2507);
DISPLAY 0.340426 (-7795 2507);
PAINT SKYBLUE (-7795 2507);
DISPLAY INVISIBLE (-7795 2507);
FORCEADD CAP..1
(-7750 2250);
FORCEPROP 0 LAST GROUP PWR_MLCC_CAP
J 0
(-7695 2102);
DISPLAY 0.638298 (-7695 2102);
PAINT BROWN (-7695 2102);
DISPLAY BOTH (-7695 2102);
FORCEPROP 1 LASTPIN (-7750 2150) $PN 2
J 0
(-7740 2130);
DISPLAY 0.617021 (-7740 2130);
PAINT GREEN (-7740 2130);
FORCEPROP 1 LASTPIN (-7750 2350) $PN 1
J 0
(-7740 2330);
DISPLAY 0.617021 (-7740 2330);
PAINT GREEN (-7740 2330);
FORCEPROP 1 LAST PACK_TYPE 0805
J 0
(-7700 2150);
DISPLAY 0.617021 (-7700 2150);
PAINT SKYBLUE (-7700 2150);
FORCEPROP 1 LAST MATERIAL X6S
J 0
(-7700 2200);
DISPLAY 0.617021 (-7700 2200);
PAINT SKYBLUE (-7700 2200);
FORCEPROP 1 LAST VOLTAGE 4V
J 0
(-7700 2250);
DISPLAY 0.638298 (-7700 2250);
PAINT SKYBLUE (-7700 2250);
FORCEPROP 1 LAST TOLERANCE 20%
J 0
(-7700 2300);
DISPLAY 0.617021 (-7700 2300);
PAINT SKYBLUE (-7700 2300);
FORCEPROP 1 LAST PART_NUMBER C95333-006
R 1
J 0
(-7800 2150);
DISPLAY 0.617021 (-7800 2150);
PAINT BLUE (-7800 2150);
FORCEPROP 1 LAST LOCATION C5P37
J 0
(-7700 2400);
DISPLAY 0.617021 (-7700 2400);
PAINT AQUA (-7700 2400);
FORCEPROP 1 LAST VALUE 47UF
J 0
(-7700 2350);
DISPLAY 0.617021 (-7700 2350);
PAINT SKYBLUE (-7700 2350);
FORCEPROP 2 LAST ROOM PVCCIN_CPU0_DECAP_VR
J 0
(-7700 2400);
DISPLAY 1.021277 (-7700 2400);
PAINT ORANGE (-7700 2400);
DISPLAY INVISIBLE (-7700 2400);
FORCEPROP 1 LAST PATH I63
J 0
(-7700 2400);
DISPLAY 0.978723 (-7700 2400);
PAINT WHITE (-7700 2400);
DISPLAY INVISIBLE (-7700 2400);
FORCEPROP 2 LAST CDS_LOCATION C5P37
J 0
(-7700 2350);
DISPLAY 0.617021 (-7700 2350);
PAINT AQUA (-7700 2350);
DISPLAY INVISIBLE (-7700 2350);
FORCEPROP 2 LAST $SEC 1
J 0
(-7700 2450);
PAINT MONO (-7700 2450);
DISPLAY INVISIBLE (-7700 2450);
FORCEPROP 2 LAST CDS_SEC 1
J 0
(-7700 2450);
PAINT MONO (-7700 2450);
DISPLAY INVISIBLE (-7700 2450);
FORCEPROP 2 LAST CDS_LIB mstr_discrete
J 0
(-7750 2250);
PAINT ORANGE (-7750 2250);
DISPLAY INVISIBLE (-7750 2250);
FORCEPROP 2 LAST BOM_COST PROC_SOCKET
J 0
(-7700 2450);
DISPLAY 1.021277 (-7700 2450);
PAINT ORANGE (-7700 2450);
DISPLAY INVISIBLE (-7700 2450);
FORCEADD PVCCIN_CPU0..1
(-7750 1850);
FORCEPROP 3 LASTPIN (-7750 1800) SIG_NAME PVCCIN_CPU0\g
J 0
(-7740 1810);
DISPLAY 0.659574 (-7740 1810);
PAINT MONO (-7740 1810);
DISPLAY INVISIBLE (-7740 1810);
FORCEPROP 1 LAST VOLTAGE 2.0V
J 0
(-7795 1807);
DISPLAY 0.340426 (-7795 1807);
PAINT SKYBLUE (-7795 1807);
DISPLAY INVISIBLE (-7795 1807);
FORCEPROP 2 LAST CDS_LIB mstr_symbols
J 0
(-7750 1850);
PAINT ORANGE (-7750 1850);
DISPLAY INVISIBLE (-7750 1850);
FORCEPROP 1 LAST BODY_TYPE PLUMBING
J 0
(-7795 1807);
DISPLAY 0.340426 (-7795 1807);
PAINT GREEN (-7795 1807);
DISPLAY INVISIBLE (-7795 1807);
FORCEPROP 1 LAST PATH I64
J 0
(-7700 1875);
DISPLAY 0.872340 (-7700 1875);
PAINT AQUA (-7700 1875);
DISPLAY INVISIBLE (-7700 1875);
FORCEPROP 1 LAST HDL_POWER PVCCIN_CPU0
J 1
(-7750 1900);
DISPLAY 0.872340 (-7750 1900);
PAINT GREEN (-7750 1900);
DISPLAY INVISIBLE (-7750 1900);
FORCEADD CAP..1
(-7750 1550);
FORCEPROP 0 LAST GROUP PWR_MLCC_CAP
J 0
(-7695 1402);
DISPLAY 0.638298 (-7695 1402);
PAINT BROWN (-7695 1402);
DISPLAY BOTH (-7695 1402);
FORCEPROP 1 LAST PACK_TYPE 0805
J 0
(-7700 1450);
DISPLAY 0.617021 (-7700 1450);
PAINT SKYBLUE (-7700 1450);
FORCEPROP 1 LAST MATERIAL X6S
J 0
(-7700 1500);
DISPLAY 0.638298 (-7700 1500);
PAINT SKYBLUE (-7700 1500);
FORCEPROP 1 LAST TOLERANCE 20%
J 0
(-7700 1550);
DISPLAY 0.617021 (-7700 1550);
PAINT SKYBLUE (-7700 1550);
FORCEPROP 1 LAST VOLTAGE 4V
J 0
(-7700 1600);
DISPLAY 0.638298 (-7700 1600);
PAINT SKYBLUE (-7700 1600);
FORCEPROP 1 LAST VALUE 47UF
J 0
(-7700 1650);
DISPLAY 0.617021 (-7700 1650);
PAINT SKYBLUE (-7700 1650);
FORCEPROP 1 LAST LOCATION C5P36
J 0
(-7700 1700);
DISPLAY 0.617021 (-7700 1700);
PAINT AQUA (-7700 1700);
FORCEPROP 1 LASTPIN (-7750 1450) $PN 2
J 0
(-7740 1430);
DISPLAY 0.617021 (-7740 1430);
PAINT GREEN (-7740 1430);
FORCEPROP 1 LASTPIN (-7750 1650) $PN 1
J 0
(-7740 1630);
DISPLAY 0.617021 (-7740 1630);
PAINT GREEN (-7740 1630);
FORCEPROP 1 LAST PART_NUMBER C95333-006
R 1
J 0
(-7800 1450);
DISPLAY 0.617021 (-7800 1450);
PAINT BLUE (-7800 1450);
FORCEPROP 2 LAST BOM_COST PROC_SOCKET
J 0
(-7700 1750);
DISPLAY 1.021277 (-7700 1750);
PAINT ORANGE (-7700 1750);
DISPLAY INVISIBLE (-7700 1750);
FORCEPROP 2 LAST CDS_LIB mstr_discrete
J 0
(-7750 1550);
PAINT ORANGE (-7750 1550);
DISPLAY INVISIBLE (-7750 1550);
FORCEPROP 2 LAST CDS_SEC 1
J 0
(-7700 1750);
DISPLAY 1.021277 (-7700 1750);
PAINT ORANGE (-7700 1750);
DISPLAY INVISIBLE (-7700 1750);
FORCEPROP 2 LAST $SEC 1
J 0
(-7700 1750);
DISPLAY 0.680851 (-7700 1750);
PAINT MONO (-7700 1750);
DISPLAY INVISIBLE (-7700 1750);
FORCEPROP 2 LAST CDS_LOCATION C5P36
J 0
(-7700 1650);
DISPLAY 0.617021 (-7700 1650);
PAINT AQUA (-7700 1650);
DISPLAY INVISIBLE (-7700 1650);
FORCEPROP 1 LAST PATH I65
J 0
(-7700 1700);
DISPLAY 0.978723 (-7700 1700);
PAINT WHITE (-7700 1700);
DISPLAY INVISIBLE (-7700 1700);
FORCEPROP 2 LAST ROOM PVCCIN_CPU0_DECAP_VR
J 0
(-7700 1700);
DISPLAY 1.021277 (-7700 1700);
PAINT ORANGE (-7700 1700);
DISPLAY INVISIBLE (-7700 1700);
FORCEADD CAP_A..1
(-800 4500);
FORCEPROP 0 LAST GROUP PWR_MCP_CAP
J 0
(-750 4200);
DISPLAY 0.638298 (-750 4200);
PAINT BROWN (-750 4200);
DISPLAY BOTH (-750 4200);
FORCEPROP 1 LAST LOCATION C6D8
J 0
(-750 4600);
DISPLAY 0.617021 (-750 4600);
PAINT AQUA (-750 4600);
FORCEPROP 1 LASTPIN (-800 4600) $PN 1
J 0
(-790 4580);
DISPLAY 0.617021 (-790 4580);
PAINT GREEN (-790 4580);
FORCEPROP 1 LAST VALUE 22.0UF
J 0
(-750 4550);
DISPLAY 0.617021 (-750 4550);
PAINT SKYBLUE (-750 4550);
FORCEPROP 1 LAST VOLTAGE 4V
J 0
(-750 4500);
DISPLAY 0.617021 (-750 4500);
PAINT SKYBLUE (-750 4500);
FORCEPROP 1 LAST TOLERANCE 20%
J 0
(-750 4450);
DISPLAY 0.617021 (-750 4450);
PAINT SKYBLUE (-750 4450);
FORCEPROP 1 LAST MATERIAL X6S
J 0
(-750 4400);
DISPLAY 0.617021 (-750 4400);
PAINT SKYBLUE (-750 4400);
FORCEPROP 1 LASTPIN (-800 4400) $PN 2
J 0
(-790 4380);
DISPLAY 0.617021 (-790 4380);
PAINT GREEN (-790 4380);
FORCEPROP 1 LAST PART_NUMBER E15431-004
J 0
(-750 4350);
DISPLAY 0.617021 (-750 4350);
PAINT BLUE (-750 4350);
FORCEPROP 1 LAST PACK_TYPE 0603V
J 0
(-750 4300);
DISPLAY 0.617021 (-750 4300);
PAINT SKYBLUE (-750 4300);
FORCEPROP 2 LAST CDS_LOCATION C6D8
J 0
(-750 4600);
DISPLAY 0.617021 (-750 4600);
PAINT AQUA (-750 4600);
DISPLAY INVISIBLE (-750 4600);
FORCEPROP 2 LAST BOM_COST PROC_SOCKET
J 0
(-750 4700);
DISPLAY 1.021277 (-750 4700);
PAINT ORANGE (-750 4700);
DISPLAY INVISIBLE (-750 4700);
FORCEPROP 2 LAST CDS_LIB dev_discrete
J 0
(-800 4500);
PAINT ORANGE (-800 4500);
DISPLAY INVISIBLE (-800 4500);
FORCEPROP 2 LAST CDS_SEC 1
J 0
(-750 4700);
PAINT MONO (-750 4700);
DISPLAY INVISIBLE (-750 4700);
FORCEPROP 2 LAST $SEC 1
J 0
(-750 4700);
PAINT MONO (-750 4700);
DISPLAY INVISIBLE (-750 4700);
FORCEPROP 1 LAST PATH I68
J 0
(-750 4650);
DISPLAY 0.978723 (-750 4650);
PAINT WHITE (-750 4650);
DISPLAY INVISIBLE (-750 4650);
FORCEPROP 2 LAST ROOM PVCCIN_CPU0_DECAP_VR
J 0
(-750 4650);
DISPLAY 1.021277 (-750 4650);
PAINT ORANGE (-750 4650);
DISPLAY INVISIBLE (-750 4650);
FORCEADD CAP_A..1
(-1050 4500);
FORCEPROP 1 LASTPIN (-1050 4400) $PN 2
J 0
(-1040 4380);
DISPLAY 0.617021 (-1040 4380);
PAINT GREEN (-1040 4380);
FORCEPROP 1 LAST PACK_TYPE 0603V
J 0
(-1000 4300);
DISPLAY 0.617021 (-1000 4300);
PAINT SKYBLUE (-1000 4300);
FORCEPROP 1 LASTPIN (-1050 4600) $PN 1
J 0
(-1040 4580);
DISPLAY 0.617021 (-1040 4580);
PAINT GREEN (-1040 4580);
FORCEPROP 1 LAST VALUE 22.0UF
J 0
(-1000 4550);
DISPLAY 0.617021 (-1000 4550);
PAINT SKYBLUE (-1000 4550);
FORCEPROP 1 LAST VOLTAGE 4V
J 0
(-1000 4500);
DISPLAY 0.617021 (-1000 4500);
PAINT SKYBLUE (-1000 4500);
FORCEPROP 1 LAST LOCATION C5D38
J 0
(-1000 4600);
DISPLAY 0.617021 (-1000 4600);
PAINT AQUA (-1000 4600);
FORCEPROP 1 LAST TOLERANCE 20%
J 0
(-1000 4450);
DISPLAY 0.617021 (-1000 4450);
PAINT SKYBLUE (-1000 4450);
FORCEPROP 1 LAST PART_NUMBER E15431-004
J 0
(-1000 4350);
DISPLAY 0.617021 (-1000 4350);
PAINT BLUE (-1000 4350);
FORCEPROP 1 LAST MATERIAL X6S
J 0
(-1000 4400);
DISPLAY 0.617021 (-1000 4400);
PAINT SKYBLUE (-1000 4400);
FORCEPROP 0 LAST GROUP PWR_MCP_CAP
J 0
(-1000 4250);
DISPLAY 0.638298 (-1000 4250);
PAINT BROWN (-1000 4250);
DISPLAY BOTH (-1000 4250);
FORCEPROP 2 LAST ROOM PVCCIN_CPU0_DECAP_VR
J 0
(-1000 4650);
DISPLAY 1.021277 (-1000 4650);
PAINT ORANGE (-1000 4650);
DISPLAY INVISIBLE (-1000 4650);
FORCEPROP 1 LAST PATH I69
J 0
(-1000 4650);
DISPLAY 0.978723 (-1000 4650);
PAINT WHITE (-1000 4650);
DISPLAY INVISIBLE (-1000 4650);
FORCEPROP 2 LAST $SEC 1
J 0
(-1000 4700);
PAINT MONO (-1000 4700);
DISPLAY INVISIBLE (-1000 4700);
FORCEPROP 2 LAST CDS_SEC 1
J 0
(-1000 4700);
PAINT MONO (-1000 4700);
DISPLAY INVISIBLE (-1000 4700);
FORCEPROP 2 LAST CDS_LIB dev_discrete
J 0
(-1050 4500);
PAINT ORANGE (-1050 4500);
DISPLAY INVISIBLE (-1050 4500);
FORCEPROP 2 LAST BOM_COST PROC_SOCKET
J 0
(-1000 4700);
DISPLAY 1.021277 (-1000 4700);
PAINT ORANGE (-1000 4700);
DISPLAY INVISIBLE (-1000 4700);
FORCEPROP 2 LAST CDS_LOCATION C5D38
J 0
(-1000 4600);
DISPLAY 0.617021 (-1000 4600);
PAINT AQUA (-1000 4600);
DISPLAY INVISIBLE (-1000 4600);
FORCEADD CAP_A..1
(-1300 4500);
FORCEPROP 1 LAST VALUE 22.0UF
J 0
(-1250 4550);
DISPLAY 0.617021 (-1250 4550);
PAINT SKYBLUE (-1250 4550);
FORCEPROP 1 LAST LOCATION C5D37
J 0
(-1250 4600);
DISPLAY 0.617021 (-1250 4600);
PAINT AQUA (-1250 4600);
FORCEPROP 1 LASTPIN (-1300 4400) $PN 2
J 0
(-1290 4380);
DISPLAY 0.617021 (-1290 4380);
PAINT GREEN (-1290 4380);
FORCEPROP 1 LASTPIN (-1300 4600) $PN 1
J 0
(-1290 4580);
DISPLAY 0.617021 (-1290 4580);
PAINT GREEN (-1290 4580);
FORCEPROP 1 LAST PACK_TYPE 0603V
J 0
(-1250 4300);
DISPLAY 0.617021 (-1250 4300);
PAINT SKYBLUE (-1250 4300);
FORCEPROP 1 LAST VOLTAGE 4V
J 0
(-1250 4500);
DISPLAY 0.617021 (-1250 4500);
PAINT SKYBLUE (-1250 4500);
FORCEPROP 1 LAST PART_NUMBER E15431-004
J 0
(-1250 4350);
DISPLAY 0.617021 (-1250 4350);
PAINT BLUE (-1250 4350);
FORCEPROP 1 LAST MATERIAL X6S
J 0
(-1250 4400);
DISPLAY 0.617021 (-1250 4400);
PAINT SKYBLUE (-1250 4400);
FORCEPROP 1 LAST TOLERANCE 20%
J 0
(-1250 4450);
DISPLAY 0.617021 (-1250 4450);
PAINT SKYBLUE (-1250 4450);
FORCEPROP 0 LAST GROUP PWR_MCP_CAP
J 0
(-1250 4200);
DISPLAY 0.638298 (-1250 4200);
PAINT BROWN (-1250 4200);
DISPLAY BOTH (-1250 4200);
FORCEPROP 2 LAST ROOM PVCCIN_CPU0_DECAP_VR
J 0
(-1250 4650);
DISPLAY 1.021277 (-1250 4650);
PAINT ORANGE (-1250 4650);
DISPLAY INVISIBLE (-1250 4650);
FORCEPROP 1 LAST PATH I70
J 0
(-1250 4650);
DISPLAY 0.978723 (-1250 4650);
PAINT WHITE (-1250 4650);
DISPLAY INVISIBLE (-1250 4650);
FORCEPROP 2 LAST $SEC 1
J 0
(-1250 4700);
PAINT MONO (-1250 4700);
DISPLAY INVISIBLE (-1250 4700);
FORCEPROP 2 LAST CDS_SEC 1
J 0
(-1250 4700);
PAINT MONO (-1250 4700);
DISPLAY INVISIBLE (-1250 4700);
FORCEPROP 2 LAST CDS_LIB dev_discrete
J 0
(-1300 4500);
PAINT ORANGE (-1300 4500);
DISPLAY INVISIBLE (-1300 4500);
FORCEPROP 2 LAST BOM_COST PROC_SOCKET
J 0
(-1250 4700);
DISPLAY 1.021277 (-1250 4700);
PAINT ORANGE (-1250 4700);
DISPLAY INVISIBLE (-1250 4700);
FORCEPROP 2 LAST CDS_LOCATION C5D37
J 0
(-1250 4600);
DISPLAY 0.617021 (-1250 4600);
PAINT AQUA (-1250 4600);
DISPLAY INVISIBLE (-1250 4600);
FORCEADD GND..1
(-3550 4225);
FORCEPROP 3 LASTPIN (-3550 4275) SIG_NAME GND\g
J 0
(-3540 4285);
DISPLAY 0.659574 (-3540 4285);
PAINT MONO (-3540 4285);
DISPLAY INVISIBLE (-3540 4285);
FORCEPROP 1 LAST HDL_POWER GND
J 0
(-3550 4375);
DISPLAY 0.893617 (-3550 4375);
PAINT GREEN (-3550 4375);
DISPLAY INVISIBLE (-3550 4375);
FORCEPROP 1 LAST PATH I71
J 0
(-3475 4225);
DISPLAY 0.872340 (-3475 4225);
PAINT AQUA (-3475 4225);
DISPLAY INVISIBLE (-3475 4225);
FORCEPROP 1 LAST BODY_TYPE PLUMBING
J 0
(-3595 4182);
DISPLAY 0.340426 (-3595 4182);
PAINT GREEN (-3595 4182);
DISPLAY INVISIBLE (-3595 4182);
FORCEPROP 1 LAST SIZE 1B
J 0
(-3475 4175);
DISPLAY 0.893617 (-3475 4175);
PAINT GREEN (-3475 4175);
DISPLAY INVISIBLE (-3475 4175);
FORCEPROP 2 LAST CDS_LIB mstr_symbols
J 0
(-3550 4225);
PAINT ORANGE (-3550 4225);
DISPLAY INVISIBLE (-3550 4225);
FORCEPROP 1 LAST VOLTAGE 0
J 0
(-3550 4225);
PAINT SKYBLUE (-3550 4225);
DISPLAY INVISIBLE (-3550 4225);
FORCEADD CAP_A..1
(-3350 3800);
FORCEPROP 0 LAST GROUP PWR_MLCC_CAP
J 0
(-3295 3552);
DISPLAY 0.638298 (-3295 3552);
PAINT BROWN (-3295 3552);
DISPLAY BOTH (-3295 3552);
FORCEPROP 1 LAST PART_NUMBER E15431-004
J 0
(-3300 3700);
DISPLAY 0.617021 (-3300 3700);
PAINT BLUE (-3300 3700);
FORCEPROP 1 LAST PACK_TYPE 0603V
J 0
(-3300 3650);
DISPLAY 0.617021 (-3300 3650);
PAINT SKYBLUE (-3300 3650);
FORCEPROP 1 LASTPIN (-3350 3700) $PN 2
J 0
(-3340 3680);
DISPLAY 0.617021 (-3340 3680);
PAINT GREEN (-3340 3680);
FORCEPROP 1 LAST VOLTAGE 4V
J 0
(-3300 3850);
DISPLAY 0.617021 (-3300 3850);
PAINT SKYBLUE (-3300 3850);
FORCEPROP 1 LAST LOCATION C6D7
J 0
(-3300 3950);
DISPLAY 0.617021 (-3300 3950);
PAINT AQUA (-3300 3950);
FORCEPROP 1 LAST TOLERANCE 20%
J 0
(-3300 3800);
DISPLAY 0.617021 (-3300 3800);
PAINT SKYBLUE (-3300 3800);
FORCEPROP 1 LASTPIN (-3350 3900) $PN 1
J 0
(-3340 3880);
DISPLAY 0.617021 (-3340 3880);
PAINT GREEN (-3340 3880);
FORCEPROP 1 LAST MATERIAL X6S
J 0
(-3300 3750);
DISPLAY 0.617021 (-3300 3750);
PAINT SKYBLUE (-3300 3750);
FORCEPROP 1 LAST VALUE 22.0UF
J 0
(-3300 3900);
DISPLAY 0.617021 (-3300 3900);
PAINT SKYBLUE (-3300 3900);
FORCEPROP 2 LAST CDS_LOCATION C6D7
J 0
(-3300 3900);
DISPLAY 0.617021 (-3300 3900);
PAINT AQUA (-3300 3900);
DISPLAY INVISIBLE (-3300 3900);
FORCEPROP 2 LAST BOM_COST PROC_SOCKET
J 0
(-3300 4000);
DISPLAY 1.021277 (-3300 4000);
PAINT ORANGE (-3300 4000);
DISPLAY INVISIBLE (-3300 4000);
FORCEPROP 2 LAST CDS_LIB dev_discrete
J 0
(-3350 3800);
PAINT ORANGE (-3350 3800);
DISPLAY INVISIBLE (-3350 3800);
FORCEPROP 2 LAST CDS_SEC 1
J 0
(-3300 4000);
PAINT MONO (-3300 4000);
DISPLAY INVISIBLE (-3300 4000);
FORCEPROP 2 LAST $SEC 1
J 0
(-3300 4000);
PAINT MONO (-3300 4000);
DISPLAY INVISIBLE (-3300 4000);
FORCEPROP 1 LAST PATH I72
J 0
(-3300 3950);
DISPLAY 0.978723 (-3300 3950);
PAINT WHITE (-3300 3950);
DISPLAY INVISIBLE (-3300 3950);
FORCEPROP 2 LAST ROOM PVCCIN_CPU0_DECAP_VR
J 0
(-3300 3950);
DISPLAY 1.021277 (-3300 3950);
PAINT ORANGE (-3300 3950);
DISPLAY INVISIBLE (-3300 3950);
FORCEADD GND..1
(-4100 3525);
FORCEPROP 3 LASTPIN (-4100 3575) SIG_NAME GND\g
J 0
(-4090 3585);
DISPLAY 0.659574 (-4090 3585);
PAINT MONO (-4090 3585);
DISPLAY INVISIBLE (-4090 3585);
FORCEPROP 1 LAST VOLTAGE 0
J 0
(-4100 3525);
PAINT SKYBLUE (-4100 3525);
DISPLAY INVISIBLE (-4100 3525);
FORCEPROP 2 LAST CDS_LIB mstr_symbols
J 0
(-4100 3525);
PAINT ORANGE (-4100 3525);
DISPLAY INVISIBLE (-4100 3525);
FORCEPROP 1 LAST SIZE 1B
J 0
(-4025 3475);
DISPLAY 0.893617 (-4025 3475);
PAINT GREEN (-4025 3475);
DISPLAY INVISIBLE (-4025 3475);
FORCEPROP 1 LAST BODY_TYPE PLUMBING
J 0
(-4145 3482);
DISPLAY 0.340426 (-4145 3482);
PAINT GREEN (-4145 3482);
DISPLAY INVISIBLE (-4145 3482);
FORCEPROP 1 LAST PATH I73
J 0
(-4025 3525);
DISPLAY 0.872340 (-4025 3525);
PAINT AQUA (-4025 3525);
DISPLAY INVISIBLE (-4025 3525);
FORCEPROP 1 LAST HDL_POWER GND
J 0
(-4100 3675);
DISPLAY 0.893617 (-4100 3675);
PAINT GREEN (-4100 3675);
DISPLAY INVISIBLE (-4100 3675);
FORCEADD CAP_A..1
(-3600 3800);
FORCEPROP 1 LAST PART_NUMBER E15431-004
J 0
(-3550 3700);
DISPLAY 0.617021 (-3550 3700);
PAINT BLUE (-3550 3700);
FORCEPROP 1 LAST PACK_TYPE 0603V
J 0
(-3550 3650);
DISPLAY 0.617021 (-3550 3650);
PAINT SKYBLUE (-3550 3650);
FORCEPROP 0 LAST GROUP PWR_MLCC_CAP
J 0
(-3545 3602);
DISPLAY 0.638298 (-3545 3602);
PAINT BROWN (-3545 3602);
DISPLAY BOTH (-3545 3602);
FORCEPROP 1 LAST TOLERANCE 20%
J 0
(-3550 3800);
DISPLAY 0.617021 (-3550 3800);
PAINT SKYBLUE (-3550 3800);
FORCEPROP 1 LASTPIN (-3600 3900) $PN 1
J 0
(-3590 3880);
DISPLAY 0.617021 (-3590 3880);
PAINT GREEN (-3590 3880);
FORCEPROP 1 LAST VOLTAGE 4V
J 0
(-3550 3850);
DISPLAY 0.617021 (-3550 3850);
PAINT SKYBLUE (-3550 3850);
FORCEPROP 1 LASTPIN (-3600 3700) $PN 2
J 0
(-3590 3680);
DISPLAY 0.617021 (-3590 3680);
PAINT GREEN (-3590 3680);
FORCEPROP 1 LAST MATERIAL X6S
J 0
(-3550 3750);
DISPLAY 0.617021 (-3550 3750);
PAINT SKYBLUE (-3550 3750);
FORCEPROP 1 LAST VALUE 22.0UF
J 0
(-3550 3900);
DISPLAY 0.617021 (-3550 3900);
PAINT SKYBLUE (-3550 3900);
FORCEPROP 1 LAST LOCATION C6D4
J 0
(-3550 3950);
DISPLAY 0.617021 (-3550 3950);
PAINT AQUA (-3550 3950);
FORCEPROP 2 LAST ROOM PVCCIN_CPU0_DECAP_VR
J 0
(-3550 3950);
DISPLAY 1.021277 (-3550 3950);
PAINT ORANGE (-3550 3950);
DISPLAY INVISIBLE (-3550 3950);
FORCEPROP 1 LAST PATH I74
J 0
(-3550 3950);
DISPLAY 0.978723 (-3550 3950);
PAINT WHITE (-3550 3950);
DISPLAY INVISIBLE (-3550 3950);
FORCEPROP 2 LAST $SEC 1
J 0
(-3550 4000);
PAINT MONO (-3550 4000);
DISPLAY INVISIBLE (-3550 4000);
FORCEPROP 2 LAST CDS_SEC 1
J 0
(-3550 4000);
PAINT MONO (-3550 4000);
DISPLAY INVISIBLE (-3550 4000);
FORCEPROP 2 LAST CDS_LIB dev_discrete
J 0
(-3600 3800);
PAINT ORANGE (-3600 3800);
DISPLAY INVISIBLE (-3600 3800);
FORCEPROP 2 LAST BOM_COST PROC_SOCKET
J 0
(-3550 4000);
DISPLAY 1.021277 (-3550 4000);
PAINT ORANGE (-3550 4000);
DISPLAY INVISIBLE (-3550 4000);
FORCEPROP 2 LAST CDS_LOCATION C6D4
J 0
(-3550 3900);
DISPLAY 0.617021 (-3550 3900);
PAINT AQUA (-3550 3900);
DISPLAY INVISIBLE (-3550 3900);
FORCEADD CAP_A..1
(-1550 4500);
FORCEPROP 0 LAST GROUP PWR_MCP_CAP
J 0
(-1500 4250);
DISPLAY 0.638298 (-1500 4250);
PAINT BROWN (-1500 4250);
DISPLAY BOTH (-1500 4250);
FORCEPROP 1 LAST TOLERANCE 20%
J 0
(-1500 4450);
DISPLAY 0.617021 (-1500 4450);
PAINT SKYBLUE (-1500 4450);
FORCEPROP 1 LAST VALUE 22.0UF
J 0
(-1500 4550);
DISPLAY 0.617021 (-1500 4550);
PAINT SKYBLUE (-1500 4550);
FORCEPROP 1 LAST LOCATION C6D5
J 0
(-1500 4600);
DISPLAY 0.617021 (-1500 4600);
PAINT AQUA (-1500 4600);
FORCEPROP 1 LAST PART_NUMBER E15431-004
J 0
(-1500 4350);
DISPLAY 0.617021 (-1500 4350);
PAINT BLUE (-1500 4350);
FORCEPROP 1 LAST PACK_TYPE 0603V
J 0
(-1500 4300);
DISPLAY 0.617021 (-1500 4300);
PAINT SKYBLUE (-1500 4300);
FORCEPROP 1 LASTPIN (-1550 4600) $PN 1
J 0
(-1540 4580);
DISPLAY 0.617021 (-1540 4580);
PAINT GREEN (-1540 4580);
FORCEPROP 1 LASTPIN (-1550 4400) $PN 2
J 0
(-1540 4380);
DISPLAY 0.617021 (-1540 4380);
PAINT GREEN (-1540 4380);
FORCEPROP 1 LAST MATERIAL X6S
J 0
(-1500 4400);
DISPLAY 0.617021 (-1500 4400);
PAINT SKYBLUE (-1500 4400);
FORCEPROP 1 LAST VOLTAGE 4V
J 0
(-1500 4500);
DISPLAY 0.617021 (-1500 4500);
PAINT SKYBLUE (-1500 4500);
FORCEPROP 2 LAST CDS_LOCATION C6D5
J 0
(-1500 4600);
DISPLAY 0.617021 (-1500 4600);
PAINT AQUA (-1500 4600);
DISPLAY INVISIBLE (-1500 4600);
FORCEPROP 2 LAST BOM_COST PROC_SOCKET
J 0
(-1500 4700);
DISPLAY 1.021277 (-1500 4700);
PAINT ORANGE (-1500 4700);
DISPLAY INVISIBLE (-1500 4700);
FORCEPROP 2 LAST CDS_LIB dev_discrete
J 0
(-1550 4500);
PAINT ORANGE (-1550 4500);
DISPLAY INVISIBLE (-1550 4500);
FORCEPROP 2 LAST CDS_SEC 1
J 0
(-1500 4700);
PAINT MONO (-1500 4700);
DISPLAY INVISIBLE (-1500 4700);
FORCEPROP 2 LAST $SEC 1
J 0
(-1500 4700);
PAINT MONO (-1500 4700);
DISPLAY INVISIBLE (-1500 4700);
FORCEPROP 1 LAST PATH I75
J 0
(-1500 4650);
DISPLAY 0.978723 (-1500 4650);
PAINT WHITE (-1500 4650);
DISPLAY INVISIBLE (-1500 4650);
FORCEPROP 2 LAST ROOM PVCCIN_CPU0_DECAP_VR
J 0
(-1500 4650);
DISPLAY 1.021277 (-1500 4650);
PAINT ORANGE (-1500 4650);
DISPLAY INVISIBLE (-1500 4650);
FORCEADD CAP_A..1
(-1800 4500);
FORCEPROP 1 LAST PACK_TYPE 0603V
J 0
(-1750 4300);
DISPLAY 0.617021 (-1750 4300);
PAINT SKYBLUE (-1750 4300);
FORCEPROP 1 LAST PART_NUMBER E15431-004
J 0
(-1750 4350);
DISPLAY 0.617021 (-1750 4350);
PAINT BLUE (-1750 4350);
FORCEPROP 1 LAST TOLERANCE 20%
J 0
(-1750 4450);
DISPLAY 0.617021 (-1750 4450);
PAINT SKYBLUE (-1750 4450);
FORCEPROP 1 LASTPIN (-1800 4400) $PN 2
J 0
(-1790 4380);
DISPLAY 0.617021 (-1790 4380);
PAINT GREEN (-1790 4380);
FORCEPROP 1 LASTPIN (-1800 4600) $PN 1
J 0
(-1790 4580);
DISPLAY 0.617021 (-1790 4580);
PAINT GREEN (-1790 4580);
FORCEPROP 1 LAST MATERIAL X6S
J 0
(-1750 4400);
DISPLAY 0.617021 (-1750 4400);
PAINT SKYBLUE (-1750 4400);
FORCEPROP 1 LAST LOCATION C6D2
J 0
(-1750 4600);
DISPLAY 0.617021 (-1750 4600);
PAINT AQUA (-1750 4600);
FORCEPROP 1 LAST VALUE 22.0UF
J 0
(-1750 4550);
DISPLAY 0.617021 (-1750 4550);
PAINT SKYBLUE (-1750 4550);
FORCEPROP 1 LAST VOLTAGE 4V
J 0
(-1750 4500);
DISPLAY 0.617021 (-1750 4500);
PAINT SKYBLUE (-1750 4500);
FORCEPROP 0 LAST GROUP PWR_MCP_CAP
J 0
(-1750 4200);
DISPLAY 0.638298 (-1750 4200);
PAINT BROWN (-1750 4200);
DISPLAY BOTH (-1750 4200);
FORCEPROP 2 LAST ROOM PVCCIN_CPU0_DECAP_VR
J 0
(-1750 4650);
DISPLAY 1.021277 (-1750 4650);
PAINT ORANGE (-1750 4650);
DISPLAY INVISIBLE (-1750 4650);
FORCEPROP 1 LAST PATH I77
J 0
(-1750 4650);
DISPLAY 0.978723 (-1750 4650);
PAINT WHITE (-1750 4650);
DISPLAY INVISIBLE (-1750 4650);
FORCEPROP 2 LAST $SEC 1
J 0
(-1750 4700);
PAINT MONO (-1750 4700);
DISPLAY INVISIBLE (-1750 4700);
FORCEPROP 2 LAST CDS_SEC 1
J 0
(-1750 4700);
PAINT MONO (-1750 4700);
DISPLAY INVISIBLE (-1750 4700);
FORCEPROP 2 LAST CDS_LIB dev_discrete
J 0
(-1800 4500);
PAINT ORANGE (-1800 4500);
DISPLAY INVISIBLE (-1800 4500);
FORCEPROP 2 LAST BOM_COST PROC_SOCKET
J 0
(-1750 4700);
DISPLAY 1.021277 (-1750 4700);
PAINT ORANGE (-1750 4700);
DISPLAY INVISIBLE (-1750 4700);
FORCEPROP 2 LAST CDS_LOCATION C6D2
J 0
(-1750 4600);
DISPLAY 0.617021 (-1750 4600);
PAINT AQUA (-1750 4600);
DISPLAY INVISIBLE (-1750 4600);
FORCEADD PVCCIO_CPU0..1
(-4100 4100);
FORCEPROP 3 LASTPIN (-4100 4050) SIG_NAME PVCCIO_CPU0\g
J 0
(-4090 4060);
DISPLAY 0.659574 (-4090 4060);
PAINT MONO (-4090 4060);
DISPLAY INVISIBLE (-4090 4060);
FORCEPROP 1 LAST HDL_POWER PVCCIO_CPU0
J 1
(-4100 4150);
DISPLAY 0.872340 (-4100 4150);
PAINT GREEN (-4100 4150);
DISPLAY INVISIBLE (-4100 4150);
FORCEPROP 1 LAST PATH I79
J 0
(-4050 4125);
DISPLAY 0.872340 (-4050 4125);
PAINT AQUA (-4050 4125);
DISPLAY INVISIBLE (-4050 4125);
FORCEPROP 1 LAST BODY_TYPE PLUMBING
J 0
(-4145 4057);
DISPLAY 0.340426 (-4145 4057);
PAINT GREEN (-4145 4057);
DISPLAY INVISIBLE (-4145 4057);
FORCEPROP 2 LAST CDS_LIB mstr_symbols
J 0
(-4100 4100);
PAINT ORANGE (-4100 4100);
DISPLAY INVISIBLE (-4100 4100);
FORCEPROP 1 LAST VOLTAGE 1.1V
J 0
(-4145 4057);
DISPLAY 0.340426 (-4145 4057);
PAINT SKYBLUE (-4145 4057);
DISPLAY INVISIBLE (-4145 4057);
FORCEADD CAP_A..1
(-3850 3800);
FORCEPROP 0 LAST GROUP PWR_MLCC_CAP
J 0
(-3795 3552);
DISPLAY 0.638298 (-3795 3552);
PAINT BROWN (-3795 3552);
DISPLAY BOTH (-3795 3552);
FORCEPROP 1 LAST VALUE 22.0UF
J 0
(-3800 3900);
DISPLAY 0.617021 (-3800 3900);
PAINT SKYBLUE (-3800 3900);
FORCEPROP 1 LASTPIN (-3850 3900) $PN 1
J 0
(-3840 3880);
DISPLAY 0.617021 (-3840 3880);
PAINT GREEN (-3840 3880);
FORCEPROP 1 LAST VOLTAGE 4V
J 0
(-3800 3850);
DISPLAY 0.617021 (-3800 3850);
PAINT SKYBLUE (-3800 3850);
FORCEPROP 1 LAST TOLERANCE 20%
J 0
(-3800 3800);
DISPLAY 0.617021 (-3800 3800);
PAINT SKYBLUE (-3800 3800);
FORCEPROP 1 LAST LOCATION C6D3
J 0
(-3800 3950);
DISPLAY 0.617021 (-3800 3950);
PAINT AQUA (-3800 3950);
FORCEPROP 1 LAST MATERIAL X6S
J 0
(-3800 3750);
DISPLAY 0.617021 (-3800 3750);
PAINT SKYBLUE (-3800 3750);
FORCEPROP 1 LAST PART_NUMBER E15431-004
J 0
(-3800 3700);
DISPLAY 0.617021 (-3800 3700);
PAINT BLUE (-3800 3700);
FORCEPROP 1 LAST PACK_TYPE 0603V
J 0
(-3800 3650);
DISPLAY 0.617021 (-3800 3650);
PAINT SKYBLUE (-3800 3650);
FORCEPROP 1 LASTPIN (-3850 3700) $PN 2
J 0
(-3840 3680);
DISPLAY 0.617021 (-3840 3680);
PAINT GREEN (-3840 3680);
FORCEPROP 2 LAST ROOM PVCCIN_CPU0_DECAP_VR
J 0
(-3800 3950);
DISPLAY 1.021277 (-3800 3950);
PAINT ORANGE (-3800 3950);
DISPLAY INVISIBLE (-3800 3950);
FORCEPROP 1 LAST PATH I80
J 0
(-3800 3950);
DISPLAY 0.978723 (-3800 3950);
PAINT WHITE (-3800 3950);
DISPLAY INVISIBLE (-3800 3950);
FORCEPROP 2 LAST $SEC 1
J 0
(-3800 4000);
PAINT MONO (-3800 4000);
DISPLAY INVISIBLE (-3800 4000);
FORCEPROP 2 LAST CDS_SEC 1
J 0
(-3800 4000);
PAINT MONO (-3800 4000);
DISPLAY INVISIBLE (-3800 4000);
FORCEPROP 2 LAST CDS_LIB dev_discrete
J 0
(-3850 3800);
PAINT ORANGE (-3850 3800);
DISPLAY INVISIBLE (-3850 3800);
FORCEPROP 2 LAST BOM_COST PROC_SOCKET
J 0
(-3800 4000);
DISPLAY 1.021277 (-3800 4000);
PAINT ORANGE (-3800 4000);
DISPLAY INVISIBLE (-3800 4000);
FORCEPROP 2 LAST CDS_LOCATION C6D3
J 0
(-3800 3900);
DISPLAY 0.617021 (-3800 3900);
PAINT AQUA (-3800 3900);
DISPLAY INVISIBLE (-3800 3900);
FORCEADD CAP_A..1
(-4100 3800);
FORCEPROP 1 LAST VALUE 22.0UF
J 0
(-4050 3900);
DISPLAY 0.617021 (-4050 3900);
PAINT SKYBLUE (-4050 3900);
FORCEPROP 0 LAST GROUP PWR_MLCC_CAP
J 0
(-4045 3602);
DISPLAY 0.638298 (-4045 3602);
PAINT BROWN (-4045 3602);
DISPLAY BOTH (-4045 3602);
FORCEPROP 1 LAST PART_NUMBER E15431-004
J 0
(-4050 3700);
DISPLAY 0.617021 (-4050 3700);
PAINT BLUE (-4050 3700);
FORCEPROP 1 LAST MATERIAL X6S
J 0
(-4050 3750);
DISPLAY 0.617021 (-4050 3750);
PAINT SKYBLUE (-4050 3750);
FORCEPROP 1 LAST VOLTAGE 4V
J 0
(-4050 3850);
DISPLAY 0.617021 (-4050 3850);
PAINT SKYBLUE (-4050 3850);
FORCEPROP 1 LAST TOLERANCE 20%
J 0
(-4050 3800);
DISPLAY 0.617021 (-4050 3800);
PAINT SKYBLUE (-4050 3800);
FORCEPROP 1 LAST PACK_TYPE 0603V
J 0
(-4050 3650);
DISPLAY 0.617021 (-4050 3650);
PAINT SKYBLUE (-4050 3650);
FORCEPROP 1 LASTPIN (-4100 3900) $PN 1
J 0
(-4090 3880);
DISPLAY 0.617021 (-4090 3880);
PAINT GREEN (-4090 3880);
FORCEPROP 1 LASTPIN (-4100 3700) $PN 2
J 0
(-4090 3680);
DISPLAY 0.617021 (-4090 3680);
PAINT GREEN (-4090 3680);
FORCEPROP 1 LAST LOCATION C6D6
J 0
(-4050 3950);
DISPLAY 0.617021 (-4050 3950);
PAINT AQUA (-4050 3950);
FORCEPROP 2 LAST CDS_LOCATION C6D6
J 0
(-4050 3900);
DISPLAY 0.617021 (-4050 3900);
PAINT AQUA (-4050 3900);
DISPLAY INVISIBLE (-4050 3900);
FORCEPROP 2 LAST BOM_COST PROC_SOCKET
J 0
(-4050 4000);
DISPLAY 1.021277 (-4050 4000);
PAINT ORANGE (-4050 4000);
DISPLAY INVISIBLE (-4050 4000);
FORCEPROP 2 LAST CDS_LIB dev_discrete
J 0
(-4100 3800);
PAINT ORANGE (-4100 3800);
DISPLAY INVISIBLE (-4100 3800);
FORCEPROP 2 LAST CDS_SEC 1
J 0
(-4050 4000);
PAINT MONO (-4050 4000);
DISPLAY INVISIBLE (-4050 4000);
FORCEPROP 2 LAST $SEC 1
J 0
(-4050 4000);
PAINT MONO (-4050 4000);
DISPLAY INVISIBLE (-4050 4000);
FORCEPROP 1 LAST PATH I81
J 0
(-4050 3950);
DISPLAY 0.978723 (-4050 3950);
PAINT WHITE (-4050 3950);
DISPLAY INVISIBLE (-4050 3950);
FORCEPROP 2 LAST ROOM PVCCIN_CPU0_DECAP_VR
J 0
(-4050 3950);
DISPLAY 1.021277 (-4050 3950);
PAINT ORANGE (-4050 3950);
DISPLAY INVISIBLE (-4050 3950);
FORCEADD CAP_A..1
(-2550 4500);
FORCEPROP 1 LAST VOLTAGE 4V
J 0
(-2500 4500);
DISPLAY 0.617021 (-2500 4500);
PAINT SKYBLUE (-2500 4500);
FORCEPROP 1 LASTPIN (-2550 4600) $PN 1
J 0
(-2540 4580);
DISPLAY 0.617021 (-2540 4580);
PAINT GREEN (-2540 4580);
FORCEPROP 1 LAST VALUE 22.0UF
J 0
(-2500 4550);
DISPLAY 0.617021 (-2500 4550);
PAINT SKYBLUE (-2500 4550);
FORCEPROP 1 LAST MATERIAL X6S
J 0
(-2500 4400);
DISPLAY 0.617021 (-2500 4400);
PAINT SKYBLUE (-2500 4400);
FORCEPROP 1 LASTPIN (-2550 4400) $PN 2
J 0
(-2540 4380);
DISPLAY 0.617021 (-2540 4380);
PAINT GREEN (-2540 4380);
FORCEPROP 1 LAST LOCATION C5D51
J 0
(-2500 4600);
DISPLAY 0.617021 (-2500 4600);
PAINT AQUA (-2500 4600);
FORCEPROP 1 LAST TOLERANCE 20%
J 0
(-2500 4450);
DISPLAY 0.617021 (-2500 4450);
PAINT SKYBLUE (-2500 4450);
FORCEPROP 1 LAST PART_NUMBER E15431-004
J 0
(-2500 4350);
DISPLAY 0.617021 (-2500 4350);
PAINT BLUE (-2500 4350);
FORCEPROP 1 LAST PACK_TYPE 0603V
J 0
(-2500 4300);
DISPLAY 0.617021 (-2500 4300);
PAINT SKYBLUE (-2500 4300);
FORCEPROP 0 LAST GROUP PWR_MCP_CAP
J 0
(-2500 4250);
DISPLAY 0.638298 (-2500 4250);
PAINT BROWN (-2500 4250);
DISPLAY BOTH (-2500 4250);
FORCEPROP 2 LAST CDS_LOCATION C5D51
J 0
(-2500 4600);
DISPLAY 0.617021 (-2500 4600);
PAINT AQUA (-2500 4600);
DISPLAY INVISIBLE (-2500 4600);
FORCEPROP 2 LAST BOM_COST PROC_SOCKET
J 0
(-2500 4700);
DISPLAY 1.021277 (-2500 4700);
PAINT ORANGE (-2500 4700);
DISPLAY INVISIBLE (-2500 4700);
FORCEPROP 2 LAST CDS_LIB dev_discrete
J 0
(-2550 4500);
PAINT ORANGE (-2550 4500);
DISPLAY INVISIBLE (-2550 4500);
FORCEPROP 2 LAST CDS_SEC 1
J 0
(-2500 4700);
PAINT MONO (-2500 4700);
DISPLAY INVISIBLE (-2500 4700);
FORCEPROP 2 LAST $SEC 1
J 0
(-2500 4700);
PAINT MONO (-2500 4700);
DISPLAY INVISIBLE (-2500 4700);
FORCEPROP 1 LAST PATH I83
J 0
(-2500 4650);
DISPLAY 0.978723 (-2500 4650);
PAINT WHITE (-2500 4650);
DISPLAY INVISIBLE (-2500 4650);
FORCEPROP 2 LAST ROOM PVCCIN_CPU0_DECAP_VR
J 0
(-2500 4650);
DISPLAY 1.021277 (-2500 4650);
PAINT ORANGE (-2500 4650);
DISPLAY INVISIBLE (-2500 4650);
FORCEADD CAP_A..1
(-2800 4500);
FORCEPROP 1 LASTPIN (-2800 4400) $PN 2
J 0
(-2790 4380);
DISPLAY 0.617021 (-2790 4380);
PAINT GREEN (-2790 4380);
FORCEPROP 1 LAST MATERIAL X6S
J 0
(-2750 4400);
DISPLAY 0.617021 (-2750 4400);
PAINT SKYBLUE (-2750 4400);
FORCEPROP 1 LAST TOLERANCE 20%
J 0
(-2750 4450);
DISPLAY 0.617021 (-2750 4450);
PAINT SKYBLUE (-2750 4450);
FORCEPROP 1 LAST VALUE 22.0UF
J 0
(-2750 4550);
DISPLAY 0.617021 (-2750 4550);
PAINT SKYBLUE (-2750 4550);
FORCEPROP 1 LAST LOCATION C5D21
J 0
(-2750 4600);
DISPLAY 0.617021 (-2750 4600);
PAINT AQUA (-2750 4600);
FORCEPROP 1 LASTPIN (-2800 4600) $PN 1
J 0
(-2790 4580);
DISPLAY 0.617021 (-2790 4580);
PAINT GREEN (-2790 4580);
FORCEPROP 1 LAST VOLTAGE 4V
J 0
(-2750 4500);
DISPLAY 0.617021 (-2750 4500);
PAINT SKYBLUE (-2750 4500);
FORCEPROP 1 LAST PART_NUMBER E15431-004
J 0
(-2750 4350);
DISPLAY 0.617021 (-2750 4350);
PAINT BLUE (-2750 4350);
FORCEPROP 1 LAST PACK_TYPE 0603V
J 0
(-2750 4300);
DISPLAY 0.617021 (-2750 4300);
PAINT SKYBLUE (-2750 4300);
FORCEPROP 0 LAST GROUP PWR_MCP_CAP
J 0
(-2750 4200);
DISPLAY 0.638298 (-2750 4200);
PAINT BROWN (-2750 4200);
DISPLAY BOTH (-2750 4200);
FORCEPROP 2 LAST ROOM PVCCIN_CPU0_DECAP_VR
J 0
(-2750 4650);
DISPLAY 1.021277 (-2750 4650);
PAINT ORANGE (-2750 4650);
DISPLAY INVISIBLE (-2750 4650);
FORCEPROP 1 LAST PATH I88
J 0
(-2750 4650);
DISPLAY 0.978723 (-2750 4650);
PAINT WHITE (-2750 4650);
DISPLAY INVISIBLE (-2750 4650);
FORCEPROP 2 LAST $SEC 1
J 0
(-2750 4700);
PAINT MONO (-2750 4700);
DISPLAY INVISIBLE (-2750 4700);
FORCEPROP 2 LAST CDS_SEC 1
J 0
(-2750 4700);
PAINT MONO (-2750 4700);
DISPLAY INVISIBLE (-2750 4700);
FORCEPROP 2 LAST CDS_LIB dev_discrete
J 0
(-2800 4500);
PAINT ORANGE (-2800 4500);
DISPLAY INVISIBLE (-2800 4500);
FORCEPROP 2 LAST BOM_COST PROC_SOCKET
J 0
(-2750 4700);
DISPLAY 1.021277 (-2750 4700);
PAINT ORANGE (-2750 4700);
DISPLAY INVISIBLE (-2750 4700);
FORCEPROP 2 LAST CDS_LOCATION C5D21
J 0
(-2750 4600);
DISPLAY 0.617021 (-2750 4600);
PAINT AQUA (-2750 4600);
DISPLAY INVISIBLE (-2750 4600);
FORCEADD CAP_A..1
(-3050 4500);
FORCEPROP 1 LAST PART_NUMBER E15431-004
J 0
(-3000 4350);
DISPLAY 0.617021 (-3000 4350);
PAINT BLUE (-3000 4350);
FORCEPROP 1 LASTPIN (-3050 4400) $PN 2
J 0
(-3040 4380);
DISPLAY 0.617021 (-3040 4380);
PAINT GREEN (-3040 4380);
FORCEPROP 1 LAST MATERIAL X6S
J 0
(-3000 4400);
DISPLAY 0.617021 (-3000 4400);
PAINT SKYBLUE (-3000 4400);
FORCEPROP 1 LAST TOLERANCE 20%
J 0
(-3000 4450);
DISPLAY 0.617021 (-3000 4450);
PAINT SKYBLUE (-3000 4450);
FORCEPROP 1 LAST LOCATION C5D50
J 0
(-3000 4600);
DISPLAY 0.617021 (-3000 4600);
PAINT AQUA (-3000 4600);
FORCEPROP 1 LASTPIN (-3050 4600) $PN 1
J 0
(-3040 4580);
DISPLAY 0.617021 (-3040 4580);
PAINT GREEN (-3040 4580);
FORCEPROP 1 LAST VOLTAGE 4V
J 0
(-3000 4500);
DISPLAY 0.617021 (-3000 4500);
PAINT SKYBLUE (-3000 4500);
FORCEPROP 1 LAST PACK_TYPE 0603V
J 0
(-3000 4300);
DISPLAY 0.617021 (-3000 4300);
PAINT SKYBLUE (-3000 4300);
FORCEPROP 1 LAST VALUE 22.0UF
J 0
(-3000 4550);
DISPLAY 0.617021 (-3000 4550);
PAINT SKYBLUE (-3000 4550);
FORCEPROP 0 LAST GROUP PWR_MCP_CAP
J 0
(-3000 4250);
DISPLAY 0.638298 (-3000 4250);
PAINT BROWN (-3000 4250);
DISPLAY BOTH (-3000 4250);
FORCEPROP 2 LAST ROOM PVCCIN_CPU0_DECAP_VR
J 0
(-3000 4650);
DISPLAY 1.021277 (-3000 4650);
PAINT ORANGE (-3000 4650);
DISPLAY INVISIBLE (-3000 4650);
FORCEPROP 1 LAST PATH I89
J 0
(-3000 4650);
DISPLAY 0.978723 (-3000 4650);
PAINT WHITE (-3000 4650);
DISPLAY INVISIBLE (-3000 4650);
FORCEPROP 2 LAST $SEC 1
J 0
(-3000 4700);
PAINT MONO (-3000 4700);
DISPLAY INVISIBLE (-3000 4700);
FORCEPROP 2 LAST CDS_SEC 1
J 0
(-3000 4700);
PAINT MONO (-3000 4700);
DISPLAY INVISIBLE (-3000 4700);
FORCEPROP 2 LAST CDS_LIB dev_discrete
J 0
(-3050 4500);
PAINT ORANGE (-3050 4500);
DISPLAY INVISIBLE (-3050 4500);
FORCEPROP 2 LAST BOM_COST PROC_SOCKET
J 0
(-3000 4700);
DISPLAY 1.021277 (-3000 4700);
PAINT ORANGE (-3000 4700);
DISPLAY INVISIBLE (-3000 4700);
FORCEPROP 2 LAST CDS_LOCATION C5D50
J 0
(-3000 4600);
DISPLAY 0.617021 (-3000 4600);
PAINT AQUA (-3000 4600);
DISPLAY INVISIBLE (-3000 4600);
FORCEADD CAP_A..1
(-3300 4500);
FORCEPROP 1 LASTPIN (-3300 4400) $PN 2
J 0
(-3290 4380);
DISPLAY 0.617021 (-3290 4380);
PAINT GREEN (-3290 4380);
FORCEPROP 1 LASTPIN (-3300 4600) $PN 1
J 0
(-3290 4580);
DISPLAY 0.617021 (-3290 4580);
PAINT GREEN (-3290 4580);
FORCEPROP 1 LAST LOCATION C5D48
J 0
(-3250 4600);
DISPLAY 0.617021 (-3250 4600);
PAINT AQUA (-3250 4600);
FORCEPROP 1 LAST VOLTAGE 4V
J 0
(-3250 4500);
DISPLAY 0.617021 (-3250 4500);
PAINT SKYBLUE (-3250 4500);
FORCEPROP 1 LAST VALUE 22.0UF
J 0
(-3250 4550);
DISPLAY 0.617021 (-3250 4550);
PAINT SKYBLUE (-3250 4550);
FORCEPROP 1 LAST TOLERANCE 20%
J 0
(-3250 4450);
DISPLAY 0.617021 (-3250 4450);
PAINT SKYBLUE (-3250 4450);
FORCEPROP 1 LAST MATERIAL X6S
J 0
(-3250 4400);
DISPLAY 0.617021 (-3250 4400);
PAINT SKYBLUE (-3250 4400);
FORCEPROP 1 LAST PART_NUMBER E15431-004
J 0
(-3250 4350);
DISPLAY 0.617021 (-3250 4350);
PAINT BLUE (-3250 4350);
FORCEPROP 1 LAST PACK_TYPE 0603V
J 0
(-3250 4300);
DISPLAY 0.617021 (-3250 4300);
PAINT SKYBLUE (-3250 4300);
FORCEPROP 0 LAST GROUP PWR_MCP_CAP
J 0
(-3250 4200);
DISPLAY 0.638298 (-3250 4200);
PAINT BROWN (-3250 4200);
DISPLAY BOTH (-3250 4200);
FORCEPROP 2 LAST ROOM PVCCIN_CPU0_DECAP_VR
J 0
(-3250 4650);
DISPLAY 1.021277 (-3250 4650);
PAINT ORANGE (-3250 4650);
DISPLAY INVISIBLE (-3250 4650);
FORCEPROP 1 LAST PATH I90
J 0
(-3250 4650);
DISPLAY 0.978723 (-3250 4650);
PAINT WHITE (-3250 4650);
DISPLAY INVISIBLE (-3250 4650);
FORCEPROP 2 LAST $SEC 1
J 0
(-3250 4700);
PAINT MONO (-3250 4700);
DISPLAY INVISIBLE (-3250 4700);
FORCEPROP 2 LAST CDS_SEC 1
J 0
(-3250 4700);
PAINT MONO (-3250 4700);
DISPLAY INVISIBLE (-3250 4700);
FORCEPROP 2 LAST CDS_LIB dev_discrete
J 0
(-3300 4500);
PAINT ORANGE (-3300 4500);
DISPLAY INVISIBLE (-3300 4500);
FORCEPROP 2 LAST BOM_COST PROC_SOCKET
J 0
(-3250 4700);
DISPLAY 1.021277 (-3250 4700);
PAINT ORANGE (-3250 4700);
DISPLAY INVISIBLE (-3250 4700);
FORCEPROP 2 LAST CDS_LOCATION C5D48
J 0
(-3250 4600);
DISPLAY 0.617021 (-3250 4600);
PAINT AQUA (-3250 4600);
DISPLAY INVISIBLE (-3250 4600);
FORCEADD CAP..1
(-3200 3150);
FORCEPROP 1 LAST PART_NUMBER E15431-001
J 0
(-3150 3000);
DISPLAY 0.617021 (-3150 3000);
PAINT BLUE (-3150 3000);
FORCEPROP 0 LAST GROUP PWR_MLCC_CAP
J 0
(-3145 2802);
DISPLAY 0.638298 (-3145 2802);
PAINT BROWN (-3145 2802);
DISPLAY BOTH (-3145 2802);
FORCEPROP 1 LAST LOCATION C5D13
J 0
(-3150 3250);
DISPLAY 0.617021 (-3150 3250);
PAINT AQUA (-3150 3250);
FORCEPROP 1 LAST VALUE 10UF
J 0
(-3150 3200);
DISPLAY 0.617021 (-3150 3200);
PAINT SKYBLUE (-3150 3200);
FORCEPROP 1 LAST MATERIAL X6S
J 0
(-3150 3050);
DISPLAY 0.617021 (-3150 3050);
PAINT SKYBLUE (-3150 3050);
FORCEPROP 1 LASTPIN (-3200 3050) $PN 2
J 0
(-3190 3030);
DISPLAY 0.617021 (-3190 3030);
PAINT GREEN (-3190 3030);
FORCEPROP 1 LASTPIN (-3200 3250) $PN 1
J 0
(-3190 3230);
DISPLAY 0.617021 (-3190 3230);
PAINT GREEN (-3190 3230);
FORCEPROP 1 LAST TOLERANCE 20%
J 0
(-3150 3100);
DISPLAY 0.617021 (-3150 3100);
PAINT SKYBLUE (-3150 3100);
FORCEPROP 1 LAST VOLTAGE 4V
J 0
(-3150 3150);
DISPLAY 0.617021 (-3150 3150);
PAINT SKYBLUE (-3150 3150);
FORCEPROP 1 LAST PACK_TYPE 0603LF
J 0
(-3150 2950);
DISPLAY 0.617021 (-3150 2950);
PAINT SKYBLUE (-3150 2950);
FORCEPROP 2 LAST CDS_LIB mstr_discrete
J 0
(-3200 3150);
PAINT ORANGE (-3200 3150);
DISPLAY INVISIBLE (-3200 3150);
FORCEPROP 2 LAST BOM_COST PROC_SOCKET
J 0
(-3150 3350);
DISPLAY 1.021277 (-3150 3350);
PAINT ORANGE (-3150 3350);
DISPLAY INVISIBLE (-3150 3350);
FORCEPROP 2 LAST CDS_SEC 1
J 0
(-3150 3350);
PAINT MONO (-3150 3350);
DISPLAY INVISIBLE (-3150 3350);
FORCEPROP 2 LAST $SEC 1
J 0
(-3150 3350);
PAINT MONO (-3150 3350);
DISPLAY INVISIBLE (-3150 3350);
FORCEPROP 2 LAST CDS_LOCATION C5D13
J 0
(-3150 3250);
DISPLAY 0.617021 (-3150 3250);
PAINT AQUA (-3150 3250);
DISPLAY INVISIBLE (-3150 3250);
FORCEPROP 1 LAST PATH I91
J 0
(-3150 3300);
DISPLAY 0.978723 (-3150 3300);
PAINT WHITE (-3150 3300);
DISPLAY INVISIBLE (-3150 3300);
FORCEPROP 2 LAST ROOM PVCCIN_CPU0_DECAP_VR
J 0
(-3150 3300);
DISPLAY 1.021277 (-3150 3300);
PAINT ORANGE (-3150 3300);
DISPLAY INVISIBLE (-3150 3300);
FORCEADD GND..1
(-4100 2775);
FORCEPROP 3 LASTPIN (-4100 2825) SIG_NAME GND\g
J 0
(-4090 2835);
DISPLAY 0.659574 (-4090 2835);
PAINT MONO (-4090 2835);
DISPLAY INVISIBLE (-4090 2835);
FORCEPROP 1 LAST VOLTAGE 0
J 0
(-4100 2775);
PAINT SKYBLUE (-4100 2775);
DISPLAY INVISIBLE (-4100 2775);
FORCEPROP 2 LAST CDS_LIB mstr_symbols
J 0
(-4100 2775);
PAINT ORANGE (-4100 2775);
DISPLAY INVISIBLE (-4100 2775);
FORCEPROP 1 LAST SIZE 1B
J 0
(-4025 2725);
DISPLAY 0.893617 (-4025 2725);
PAINT GREEN (-4025 2725);
DISPLAY INVISIBLE (-4025 2725);
FORCEPROP 1 LAST BODY_TYPE PLUMBING
J 0
(-4145 2732);
DISPLAY 0.340426 (-4145 2732);
PAINT GREEN (-4145 2732);
DISPLAY INVISIBLE (-4145 2732);
FORCEPROP 1 LAST PATH I92
J 0
(-4025 2775);
DISPLAY 0.872340 (-4025 2775);
PAINT AQUA (-4025 2775);
DISPLAY INVISIBLE (-4025 2775);
FORCEPROP 1 LAST HDL_POWER GND
J 0
(-4100 2925);
DISPLAY 0.893617 (-4100 2925);
PAINT GREEN (-4100 2925);
DISPLAY INVISIBLE (-4100 2925);
FORCEADD CAP..1
(-3500 3150);
FORCEPROP 0 LAST GROUP PWR_MLCC_CAP
J 0
(-3445 2902);
DISPLAY 0.638298 (-3445 2902);
PAINT BROWN (-3445 2902);
DISPLAY BOTH (-3445 2902);
FORCEPROP 1 LAST PACK_TYPE 0603LF
J 0
(-3450 2950);
DISPLAY 0.617021 (-3450 2950);
PAINT SKYBLUE (-3450 2950);
FORCEPROP 1 LAST PART_NUMBER E15431-001
J 0
(-3465 3005);
DISPLAY 0.617021 (-3465 3005);
PAINT BLUE (-3465 3005);
FORCEPROP 1 LASTPIN (-3500 3050) $PN 2
J 0
(-3490 3030);
DISPLAY 0.617021 (-3490 3030);
PAINT GREEN (-3490 3030);
FORCEPROP 1 LASTPIN (-3500 3250) $PN 1
J 0
(-3490 3230);
DISPLAY 0.617021 (-3490 3230);
PAINT GREEN (-3490 3230);
FORCEPROP 1 LAST MATERIAL X6S
J 0
(-3450 3050);
DISPLAY 0.617021 (-3450 3050);
PAINT SKYBLUE (-3450 3050);
FORCEPROP 1 LAST VOLTAGE 4V
J 0
(-3450 3150);
DISPLAY 0.617021 (-3450 3150);
PAINT SKYBLUE (-3450 3150);
FORCEPROP 1 LAST TOLERANCE 20%
J 0
(-3450 3100);
DISPLAY 0.617021 (-3450 3100);
PAINT SKYBLUE (-3450 3100);
FORCEPROP 1 LAST LOCATION C5D11
J 0
(-3450 3250);
DISPLAY 0.617021 (-3450 3250);
PAINT AQUA (-3450 3250);
FORCEPROP 1 LAST VALUE 10UF
J 0
(-3450 3200);
DISPLAY 0.617021 (-3450 3200);
PAINT SKYBLUE (-3450 3200);
FORCEPROP 2 LAST ROOM PVCCIN_CPU0_DECAP_VR
J 0
(-3450 3300);
DISPLAY 1.021277 (-3450 3300);
PAINT ORANGE (-3450 3300);
DISPLAY INVISIBLE (-3450 3300);
FORCEPROP 1 LAST PATH I93
J 0
(-3450 3300);
DISPLAY 0.978723 (-3450 3300);
PAINT WHITE (-3450 3300);
DISPLAY INVISIBLE (-3450 3300);
FORCEPROP 2 LAST CDS_LOCATION C5D11
J 0
(-3450 3250);
DISPLAY 0.617021 (-3450 3250);
PAINT AQUA (-3450 3250);
DISPLAY INVISIBLE (-3450 3250);
FORCEPROP 2 LAST $SEC 1
J 0
(-3450 3350);
PAINT MONO (-3450 3350);
DISPLAY INVISIBLE (-3450 3350);
FORCEPROP 2 LAST CDS_SEC 1
J 0
(-3450 3350);
PAINT MONO (-3450 3350);
DISPLAY INVISIBLE (-3450 3350);
FORCEPROP 2 LAST BOM_COST PROC_SOCKET
J 0
(-3450 3350);
DISPLAY 1.021277 (-3450 3350);
PAINT ORANGE (-3450 3350);
DISPLAY INVISIBLE (-3450 3350);
FORCEPROP 2 LAST CDS_LIB mstr_discrete
J 0
(-3500 3150);
PAINT ORANGE (-3500 3150);
DISPLAY INVISIBLE (-3500 3150);
FORCEADD CAP..1
(-3800 3150);
FORCEPROP 1 LAST VALUE 10UF
J 0
(-3750 3200);
DISPLAY 0.617021 (-3750 3200);
PAINT SKYBLUE (-3750 3200);
FORCEPROP 1 LAST VOLTAGE 4V
J 0
(-3750 3150);
DISPLAY 0.617021 (-3750 3150);
PAINT SKYBLUE (-3750 3150);
FORCEPROP 1 LASTPIN (-3800 3050) $PN 2
J 0
(-3790 3030);
DISPLAY 0.617021 (-3790 3030);
PAINT GREEN (-3790 3030);
FORCEPROP 1 LASTPIN (-3800 3250) $PN 1
J 0
(-3790 3230);
DISPLAY 0.617021 (-3790 3230);
PAINT GREEN (-3790 3230);
FORCEPROP 1 LAST TOLERANCE 20%
J 0
(-3750 3100);
DISPLAY 0.617021 (-3750 3100);
PAINT SKYBLUE (-3750 3100);
FORCEPROP 1 LAST MATERIAL X6S
J 0
(-3750 3050);
DISPLAY 0.617021 (-3750 3050);
PAINT SKYBLUE (-3750 3050);
FORCEPROP 1 LAST PART_NUMBER E15431-001
J 0
(-3750 3000);
DISPLAY 0.617021 (-3750 3000);
PAINT BLUE (-3750 3000);
FORCEPROP 1 LAST PACK_TYPE 0603LF
J 0
(-3750 2950);
DISPLAY 0.617021 (-3750 2950);
PAINT SKYBLUE (-3750 2950);
FORCEPROP 0 LAST GROUP PWR_MLCC_CAP
J 0
(-3770 2802);
DISPLAY 0.638298 (-3770 2802);
PAINT BROWN (-3770 2802);
DISPLAY BOTH (-3770 2802);
FORCEPROP 1 LAST LOCATION C5D12
J 0
(-3750 3250);
DISPLAY 0.617021 (-3750 3250);
PAINT AQUA (-3750 3250);
FORCEPROP 2 LAST ROOM PVCCIN_CPU0_DECAP_VR
J 0
(-3750 3300);
DISPLAY 1.021277 (-3750 3300);
PAINT ORANGE (-3750 3300);
DISPLAY INVISIBLE (-3750 3300);
FORCEPROP 1 LAST PATH I94
J 0
(-3750 3300);
DISPLAY 0.978723 (-3750 3300);
PAINT WHITE (-3750 3300);
DISPLAY INVISIBLE (-3750 3300);
FORCEPROP 2 LAST CDS_LOCATION C5D12
J 0
(-3750 3250);
DISPLAY 0.617021 (-3750 3250);
PAINT AQUA (-3750 3250);
DISPLAY INVISIBLE (-3750 3250);
FORCEPROP 2 LAST $SEC 1
J 0
(-3750 3350);
PAINT MONO (-3750 3350);
DISPLAY INVISIBLE (-3750 3350);
FORCEPROP 2 LAST CDS_SEC 1
J 0
(-3750 3350);
PAINT MONO (-3750 3350);
DISPLAY INVISIBLE (-3750 3350);
FORCEPROP 2 LAST BOM_COST PROC_SOCKET
J 0
(-3750 3350);
DISPLAY 1.021277 (-3750 3350);
PAINT ORANGE (-3750 3350);
DISPLAY INVISIBLE (-3750 3350);
FORCEPROP 2 LAST CDS_LIB mstr_discrete
J 0
(-3800 3150);
PAINT ORANGE (-3800 3150);
DISPLAY INVISIBLE (-3800 3150);
FORCEADD CAP_A..1
(-3550 4500);
FORCEPROP 1 LAST MATERIAL X6S
J 0
(-3500 4400);
DISPLAY 0.617021 (-3500 4400);
PAINT SKYBLUE (-3500 4400);
FORCEPROP 1 LAST TOLERANCE 20%
J 0
(-3500 4450);
DISPLAY 0.617021 (-3500 4450);
PAINT SKYBLUE (-3500 4450);
FORCEPROP 1 LAST LOCATION C5D23
J 0
(-3500 4600);
DISPLAY 0.617021 (-3500 4600);
PAINT AQUA (-3500 4600);
FORCEPROP 1 LASTPIN (-3550 4400) $PN 2
J 0
(-3540 4380);
DISPLAY 0.617021 (-3540 4380);
PAINT GREEN (-3540 4380);
FORCEPROP 1 LASTPIN (-3550 4600) $PN 1
J 0
(-3540 4580);
DISPLAY 0.617021 (-3540 4580);
PAINT GREEN (-3540 4580);
FORCEPROP 1 LAST VALUE 22.0UF
J 0
(-3500 4550);
DISPLAY 0.617021 (-3500 4550);
PAINT SKYBLUE (-3500 4550);
FORCEPROP 1 LAST VOLTAGE 4V
J 0
(-3500 4500);
DISPLAY 0.617021 (-3500 4500);
PAINT SKYBLUE (-3500 4500);
FORCEPROP 1 LAST PACK_TYPE 0603V
J 0
(-3500 4300);
DISPLAY 0.617021 (-3500 4300);
PAINT SKYBLUE (-3500 4300);
FORCEPROP 1 LAST PART_NUMBER E15431-004
J 0
(-3500 4350);
DISPLAY 0.617021 (-3500 4350);
PAINT BLUE (-3500 4350);
FORCEPROP 0 LAST GROUP PWR_MCP_CAP
J 0
(-3500 4250);
DISPLAY 0.638298 (-3500 4250);
PAINT BROWN (-3500 4250);
DISPLAY BOTH (-3500 4250);
FORCEPROP 2 LAST ROOM PVCCIN_CPU0_DECAP_VR
J 0
(-3500 4650);
DISPLAY 1.021277 (-3500 4650);
PAINT ORANGE (-3500 4650);
DISPLAY INVISIBLE (-3500 4650);
FORCEPROP 1 LAST PATH I98
J 0
(-3500 4650);
DISPLAY 0.978723 (-3500 4650);
PAINT WHITE (-3500 4650);
DISPLAY INVISIBLE (-3500 4650);
FORCEPROP 2 LAST $SEC 1
J 0
(-3500 4700);
PAINT MONO (-3500 4700);
DISPLAY INVISIBLE (-3500 4700);
FORCEPROP 2 LAST CDS_SEC 1
J 0
(-3500 4700);
PAINT MONO (-3500 4700);
DISPLAY INVISIBLE (-3500 4700);
FORCEPROP 2 LAST CDS_LIB dev_discrete
J 0
(-3550 4500);
PAINT ORANGE (-3550 4500);
DISPLAY INVISIBLE (-3550 4500);
FORCEPROP 2 LAST BOM_COST PROC_SOCKET
J 0
(-3500 4700);
DISPLAY 1.021277 (-3500 4700);
PAINT ORANGE (-3500 4700);
DISPLAY INVISIBLE (-3500 4700);
FORCEPROP 2 LAST CDS_LOCATION C5D23
J 0
(-3500 4600);
DISPLAY 0.617021 (-3500 4600);
PAINT AQUA (-3500 4600);
DISPLAY INVISIBLE (-3500 4600);
FORCEADD PVSA_CPU0..1
(-4100 3450);
FORCEPROP 3 LASTPIN (-4100 3400) SIG_NAME PVSA_CPU0\g
J 0
(-4090 3410);
DISPLAY 0.659574 (-4090 3410);
PAINT MONO (-4090 3410);
DISPLAY INVISIBLE (-4090 3410);
FORCEPROP 1 LAST HDL_POWER PVSA_CPU0
J 1
(-4100 3500);
DISPLAY 0.872340 (-4100 3500);
PAINT GREEN (-4100 3500);
DISPLAY INVISIBLE (-4100 3500);
FORCEPROP 1 LAST PATH I99
J 0
(-4050 3475);
DISPLAY 0.872340 (-4050 3475);
PAINT AQUA (-4050 3475);
DISPLAY INVISIBLE (-4050 3475);
FORCEPROP 1 LAST BODY_TYPE PLUMBING
J 0
(-4145 3407);
DISPLAY 0.340426 (-4145 3407);
PAINT GREEN (-4145 3407);
DISPLAY INVISIBLE (-4145 3407);
FORCEPROP 2 LAST CDS_LIB mstr_symbols
J 0
(-4100 3450);
PAINT ORANGE (-4100 3450);
DISPLAY INVISIBLE (-4100 3450);
FORCEPROP 1 LAST VOLTAGE 1.1V
J 0
(-4145 3407);
DISPLAY 0.340426 (-4145 3407);
PAINT SKYBLUE (-4145 3407);
DISPLAY INVISIBLE (-4145 3407);
FORCEADD INTEL_CORP_BPAGE..1
(0 0);
FORCEPROP 1 LAST CDS_CON_LAST_MODIFIED Fri Jun 16 17:48:15 2017
J 0
(-1425 325);
PAINT ORANGE (-1425 325);
DISPLAY INVISIBLE (-1425 325);
FORCEPROP 1 LAST CUSTOM_TXT_CDS <CURRENT_DESIGN_SHEET> OF <TOTAL_DESIGN_SHEETS>
J 0
(-500 25);
PAINT ORANGE (-500 25);
FORCEPROP 1 LAST CUSTOM_TXT_CDS <CON_LAST_MODIFIED>
J 0
(-4000 100);
PAINT ORANGE (-4000 100);
FORCEPROP 2 LAST CUSTOM_TXT_CDS <XR_PAGE_TITLE>
J 0
(-7890 5250);
DISPLAY 0.638298 (-7890 5250);
PAINT PINK (-7890 5250);
DISPLAY INVISIBLE (-7890 5250);
FORCEPROP 1 LAST SCH_TITLE CPU0 DECOUPLING CAVITY CAPS
J 0
(-7950 50);
DISPLAY 1.212766 (-7950 50);
PAINT ORANGE (-7950 50);
FORCEPROP 2 LAST CDS_LIB mstr_symbols
J 0
(0 0);
PAINT MONO (0 0);
DISPLAY INVISIBLE (0 0);
FORCEPROP 2 LAST PAGE_BORDER TRUE
J 0
(-7890 5250);
DISPLAY 0.638298 (-7890 5250);
PAINT PINK (-7890 5250);
DISPLAY INVISIBLE (-7890 5250);
FORCEPROP 1 LAST COMMENT_BODY TRUE
J 0
(12 12);
DISPLAY 0.468085 (12 12);
PAINT GREEN (12 12);
DISPLAY INVISIBLE (12 12);
FORCEPROP 2 LAST CDS_XR_PAGE_TITLE CR-42 : @BASEBOARD_FAB2_LIB.BASEBOARD_FAB2(SCH_1):PAGE42
J 0
(-7890 5250);
DISPLAY 0.638298 (-7890 5250);
PAINT PINK (-7890 5250);
DISPLAY INVISIBLE (-7890 5250);
FORCEADD DESIGN_NOTE..1
(-1150 800);
PAINT PURPLE (-1150 800);
FORCEPROP 0 LAST L1 * HIGH TEMPERATURE
J 0
(-1350 675);
PAINT VIOLET (-1350 675);
FORCEPROP 0 LAST L2 CAPACITORS.
J 0
(-1350 625);
PAINT VIOLET (-1350 625);
FORCEPROP 0 LAST L3 * TO BE PLACED IN
J 0
(-1350 550);
PAINT VIOLET (-1350 550);
FORCEPROP 0 LAST L4 SKT 0 CAVITY (BOTTOM, 98MIL/2.49MM)
J 0
(-1350 500);
PAINT VIOLET (-1350 500);
FORCEPROP 1 LAST COMMENT_BODY TRUE
J 0
(-1125 900);
DISPLAY 1.319149 (-1125 900);
PAINT GREEN (-1125 900);
DISPLAY INVISIBLE (-1125 900);
FORCEPROP 2 LAST CDS_LIB mstr_symbols
J 0
(-1150 800);
PAINT MONO (-1150 800);
DISPLAY INVISIBLE (-1150 800);
FORCEADD DESIGN_NOTE..1
(-2500 3400);
PAINT PURPLE (-2500 3400);
FORCEPROP 0 LAST L2 CAPACITORS.
J 0
(-2700 3225);
PAINT VIOLET (-2700 3225);
FORCEPROP 0 LAST L3 * TO BE PLACED IN
J 0
(-2700 3150);
PAINT VIOLET (-2700 3150);
FORCEPROP 0 LAST L1 * HIGH TEMPERATURE
J 0
(-2700 3275);
PAINT VIOLET (-2700 3275);
FORCEPROP 0 LAST L4 SKT 0 CAVITY (TOP,48.11MIL/1.22MM)
J 0
(-2700 3100);
PAINT VIOLET (-2700 3100);
FORCEPROP 2 LAST CDS_LIB mstr_symbols
J 0
(-2500 3400);
PAINT MONO (-2500 3400);
DISPLAY INVISIBLE (-2500 3400);
FORCEPROP 1 LAST COMMENT_BODY TRUE
J 0
(-2475 3500);
DISPLAY 1.319149 (-2475 3500);
PAINT GREEN (-2475 3500);
DISPLAY INVISIBLE (-2475 3500);
WIRE 16 -1 (-5950 3575)(-5950 3600);
WIRE 16 -1 (-5950 3600)(-5800 3600);
WIRE 16 -1 (-5500 3600)(-5800 3600);
WIRE 16 -1 (-5800 3700)(-5800 3600);
WIRE 16 -1 (-5200 3600)(-5500 3600);
WIRE 16 -1 (-5500 3700)(-5500 3600);
WIRE 16 -1 (-4900 3600)(-5200 3600);
WIRE 16 -1 (-5200 3700)(-5200 3600);
WIRE 16 -1 (-4600 3600)(-4900 3600);
WIRE 16 -1 (-4900 3700)(-4900 3600);
WIRE 16 -1 (-4600 3700)(-4600 3600);
WIRE 16 -1 (-5950 4275)(-5950 4300);
WIRE 16 -1 (-5950 4300)(-5650 4300);
WIRE 16 -1 (-5950 4400)(-5950 4300);
WIRE 16 -1 (-5350 4300)(-5650 4300);
WIRE 16 -1 (-5650 4400)(-5650 4300);
WIRE 16 -1 (-5050 4300)(-5350 4300);
WIRE 16 -1 (-5350 4400)(-5350 4300);
WIRE 16 -1 (-4750 4300)(-5050 4300);
WIRE 16 -1 (-5050 4400)(-5050 4300);
WIRE 16 -1 (-4450 4300)(-4750 4300);
WIRE 16 -1 (-4750 4400)(-4750 4300);
WIRE 16 -1 (-4450 4400)(-4450 4300);
WIRE 16 -1 (-5950 2925)(-5950 2950);
WIRE 16 -1 (-5950 2950)(-5300 2950);
WIRE 16 -1 (-5950 3050)(-5950 2950);
WIRE 16 -1 (-5000 2950)(-5300 2950);
WIRE 16 -1 (-5300 3050)(-5300 2950);
WIRE 16 -1 (-4700 2950)(-5000 2950);
WIRE 16 -1 (-5000 3050)(-5000 2950);
WIRE 16 -1 (-4700 3050)(-4700 2950);
WIRE 16 -1 (-5950 4700)(-5950 4750);
WIRE 16 -1 (-5650 4700)(-5950 4700);
WIRE 16 -1 (-5950 4600)(-5950 4700);
WIRE 16 -1 (-5350 4700)(-5650 4700);
WIRE 16 -1 (-5650 4600)(-5650 4700);
WIRE 16 -1 (-5050 4700)(-5350 4700);
WIRE 16 -1 (-5350 4600)(-5350 4700);
WIRE 16 -1 (-4750 4700)(-5050 4700);
WIRE 16 -1 (-5050 4600)(-5050 4700);
WIRE 16 -1 (-4450 4700)(-4750 4700);
WIRE 16 -1 (-4750 4700)(-4750 4600);
WIRE 16 -1 (-4450 4700)(-4450 4600);
WIRE 16 -1 (-5950 4000)(-5950 4050);
WIRE 16 -1 (-5800 4000)(-5950 4000);
WIRE 16 -1 (-5500 4000)(-5800 4000);
WIRE 16 -1 (-5800 3900)(-5800 4000);
WIRE 16 -1 (-5200 4000)(-5500 4000);
WIRE 16 -1 (-5500 3900)(-5500 4000);
WIRE 16 -1 (-4900 4000)(-5200 4000);
WIRE 16 -1 (-5200 3900)(-5200 4000);
WIRE 16 -1 (-4600 4000)(-4900 4000);
WIRE 16 -1 (-4900 3900)(-4900 4000);
WIRE 16 -1 (-4600 4000)(-4600 3900);
WIRE 16 -1 (-5950 3350)(-5950 3375);
WIRE 16 -1 (-5300 3350)(-5950 3350);
WIRE 16 -1 (-5950 3350)(-5950 3250);
WIRE 16 -1 (-5000 3350)(-5300 3350);
WIRE 16 -1 (-5300 3250)(-5300 3350);
WIRE 16 -1 (-4700 3350)(-5000 3350);
WIRE 16 -1 (-5000 3350)(-5000 3250);
WIRE 16 -1 (-4700 3350)(-4700 3250);
WIRE 16 -1 (-7750 4275)(-7750 4300);
WIRE 16 -1 (-7750 4300)(-7050 4300);
WIRE 16 -1 (-7750 4400)(-7750 4300);
WIRE 16 -1 (-6750 4300)(-7050 4300);
WIRE 16 -1 (-7050 4400)(-7050 4300);
WIRE 16 -1 (-6750 4400)(-6750 4300);
WIRE 16 -1 (-7750 3575)(-7750 3600);
WIRE 16 -1 (-7750 3600)(-7050 3600);
WIRE 16 -1 (-7750 3700)(-7750 3600);
WIRE 16 -1 (-6750 3600)(-7050 3600);
WIRE 16 -1 (-7050 3700)(-7050 3600);
WIRE 16 -1 (-6750 3700)(-6750 3600);
WIRE 16 -1 (-7750 2875)(-7750 2900);
WIRE 16 -1 (-7750 2900)(-7250 2900);
WIRE 16 -1 (-7750 3000)(-7750 2900);
WIRE 16 -1 (-6950 2900)(-7250 2900);
WIRE 16 -1 (-7250 3000)(-7250 2900);
WIRE 16 -1 (-6650 2900)(-6950 2900);
WIRE 16 -1 (-6950 3000)(-6950 2900);
WIRE 16 -1 (-6650 3000)(-6650 2900);
WIRE 16 -1 (-7750 4700)(-7750 4750);
WIRE 16 -1 (-7750 4700)(-7050 4700);
WIRE 16 -1 (-7750 4700)(-7750 4600);
WIRE 16 -1 (-6750 4700)(-7050 4700);
WIRE 16 -1 (-7050 4600)(-7050 4700);
WIRE 16 -1 (-6750 4700)(-6750 4600);
WIRE 16 -1 (-7750 3300)(-7750 3350);
WIRE 16 -1 (-7750 3300)(-7250 3300);
WIRE 16 -1 (-7750 3300)(-7750 3200);
WIRE 16 -1 (-6950 3300)(-7250 3300);
WIRE 16 -1 (-7250 3200)(-7250 3300);
WIRE 16 -1 (-6650 3300)(-6950 3300);
WIRE 16 -1 (-6950 3200)(-6950 3300);
WIRE 16 -1 (-6650 3300)(-6650 3200);
WIRE 16 -1 (-3550 4650)(-3550 4675);
WIRE 16 -1 (-3550 4650)(-3300 4650);
WIRE 16 -1 (-3550 4650)(-3550 4600);
WIRE 16 -1 (-3300 4650)(-3050 4650);
WIRE 16 -1 (-3300 4600)(-3300 4650);
WIRE 16 -1 (-3050 4650)(-2800 4650);
WIRE 16 -1 (-3050 4600)(-3050 4650);
WIRE 16 -1 (-2800 4650)(-2550 4650);
WIRE 16 -1 (-2800 4600)(-2800 4650);
WIRE 16 -1 (-2550 4650)(-2300 4650);
WIRE 16 -1 (-2550 4650)(-2550 4600);
WIRE 16 -1 (-2300 4650)(-2050 4650);
WIRE 16 -1 (-2300 4650)(-2300 4600);
WIRE 16 -1 (-2050 4650)(-1800 4650);
WIRE 16 -1 (-2050 4650)(-2050 4600);
WIRE 16 -1 (-1800 4650)(-1550 4650);
WIRE 16 -1 (-1800 4650)(-1800 4600);
WIRE 16 -1 (-1550 4650)(-1300 4650);
WIRE 16 -1 (-1550 4600)(-1550 4650);
WIRE 16 -1 (-1300 4650)(-1050 4650);
WIRE 16 -1 (-1300 4600)(-1300 4650);
WIRE 16 -1 (-800 4650)(-1050 4650);
WIRE 16 -1 (-1050 4600)(-1050 4650);
WIRE 16 -1 (-550 4650)(-800 4650);
WIRE 16 -1 (-800 4650)(-800 4600);
WIRE 16 -1 (-550 4650)(-550 4600);
WIRE 16 -1 (-4750 2450)(-4750 2475);
WIRE 16 -1 (-4750 2450)(-4500 2450);
WIRE 16 -1 (-4750 2325)(-4750 2450);
WIRE 16 -1 (-4250 2450)(-4500 2450);
WIRE 16 -1 (-4500 2325)(-4500 2450);
WIRE 16 -1 (-4000 2450)(-4250 2450);
WIRE 16 -1 (-4250 2325)(-4250 2450);
WIRE 16 -1 (-4000 2450)(-3750 2450);
WIRE 16 -1 (-4000 2325)(-4000 2450);
WIRE 16 -1 (-3500 2450)(-3750 2450);
WIRE 16 -1 (-3750 2325)(-3750 2450);
WIRE 16 -1 (-3500 2450)(-3250 2450);
WIRE 16 -1 (-3500 2450)(-3500 2325);
WIRE 16 -1 (-3000 2450)(-3250 2450);
WIRE 16 -1 (-3250 2325)(-3250 2450);
WIRE 16 -1 (-3000 2450)(-2750 2450);
WIRE 16 -1 (-3000 2325)(-3000 2450);
WIRE 16 -1 (-2500 2450)(-2750 2450);
WIRE 16 -1 (-2750 2325)(-2750 2450);
WIRE 16 -1 (-2500 2450)(-2250 2450);
WIRE 16 -1 (-2500 2450)(-2500 2325);
WIRE 16 -1 (-2000 2450)(-2250 2450);
WIRE 16 -1 (-2250 2325)(-2250 2450);
WIRE 16 -1 (-2000 2450)(-1750 2450);
WIRE 16 -1 (-2000 2325)(-2000 2450);
WIRE 16 -1 (-1500 2450)(-1750 2450);
WIRE 16 -1 (-1750 2450)(-1750 2325);
WIRE 16 -1 (-1500 2450)(-1250 2450);
WIRE 16 -1 (-1500 2325)(-1500 2450);
WIRE 16 -1 (-1250 2450)(-1000 2450);
WIRE 16 -1 (-1250 2325)(-1250 2450);
WIRE 16 -1 (-1000 2450)(-750 2450);
WIRE 16 -1 (-1000 2325)(-1000 2450);
WIRE 16 -1 (-750 2450)(-750 2325);
WIRE 16 -1 (-3200 1150)(-3200 1225);
WIRE 16 -1 (-2850 1150)(-3200 1150);
WIRE 16 -1 (-3200 1050)(-3200 1150);
WIRE 16 -1 (-2850 1150)(-2550 1150);
WIRE 16 -1 (-2850 1050)(-2850 1150);
WIRE 16 -1 (-2250 1150)(-2550 1150);
WIRE 16 -1 (-2550 1050)(-2550 1150);
WIRE 16 -1 (-2250 1150)(-1950 1150);
WIRE 16 -1 (-2250 1050)(-2250 1150);
WIRE 16 -1 (-1950 1150)(-1950 1050);
WIRE 16 -1 (-1800 4025)(-1800 4000);
WIRE 16 -1 (-1800 4000)(-1550 4000);
WIRE 16 -1 (-1800 4000)(-1800 3950);
WIRE 16 -1 (-1550 4000)(-1300 4000);
WIRE 16 -1 (-1550 4000)(-1550 3950);
WIRE 16 -1 (-1300 4000)(-1050 4000);
WIRE 16 -1 (-1300 4000)(-1300 3950);
WIRE 16 -1 (-1050 4000)(-800 4000);
WIRE 16 -1 (-1050 4000)(-1050 3950);
WIRE 16 -1 (-550 4000)(-800 4000);
WIRE 16 -1 (-800 4000)(-800 3950);
WIRE 16 -1 (-550 4000)(-550 3950);
WIRE 16 -1 (-6550 1100)(-6550 950);
WIRE 16 -1 (-1950 675)(-1950 700);
WIRE 16 -1 (-1950 700)(-2250 700);
WIRE 16 -1 (-1950 850)(-1950 700);
WIRE 16 -1 (-2250 700)(-2550 700);
WIRE 16 -1 (-2250 850)(-2250 700);
WIRE 16 -1 (-2850 700)(-2550 700);
WIRE 16 -1 (-2550 850)(-2550 700);
WIRE 16 -1 (-3200 700)(-2850 700);
WIRE 16 -1 (-2850 850)(-2850 700);
WIRE 16 -1 (-3200 850)(-3200 700);
WIRE 16 -1 (-5350 2350)(-5350 2500);
WIRE 16 -1 (-5950 1450)(-5950 1325);
WIRE 16 -1 (-5050 1650)(-5050 1800);
WIRE 16 -1 (-3850 675)(-3850 700);
WIRE 16 -1 (-3850 700)(-4150 700);
WIRE 16 -1 (-3850 850)(-3850 700);
WIRE 16 -1 (-4150 700)(-4450 700);
WIRE 16 -1 (-4150 850)(-4150 700);
WIRE 16 -1 (-4450 850)(-4450 700);
WIRE 16 -1 (-5350 2150)(-5350 2025);
WIRE 16 -1 (-1150 1150)(-1150 1075);
WIRE 16 -1 (-1150 1450)(-1150 1350);
WIRE 16 -1 (-800 3325)(-800 3300);
WIRE 16 -1 (-800 3300)(-550 3300);
WIRE 16 -1 (-800 3300)(-800 3250);
WIRE 16 -1 (-550 3300)(-550 3250);
WIRE 16 -1 (-800 2925)(-800 2950);
WIRE 16 -1 (-800 2950)(-550 2950);
WIRE 16 -1 (-800 3050)(-800 2950);
WIRE 16 -1 (-550 2950)(-550 3050);
WIRE 16 -1 (-1800 3625)(-1800 3650);
WIRE 16 -1 (-1800 3650)(-1550 3650);
WIRE 16 -1 (-1800 3750)(-1800 3650);
WIRE 16 -1 (-1550 3650)(-1300 3650);
WIRE 16 -1 (-1550 3750)(-1550 3650);
WIRE 16 -1 (-1300 3650)(-1050 3650);
WIRE 16 -1 (-1300 3750)(-1300 3650);
WIRE 16 -1 (-1050 3650)(-800 3650);
WIRE 16 -1 (-1050 3750)(-1050 3650);
WIRE 16 -1 (-800 3650)(-550 3650);
WIRE 16 -1 (-800 3750)(-800 3650);
WIRE 16 -1 (-550 3750)(-550 3650);
WIRE 16 -1 (-4450 1150)(-4450 1200);
WIRE 16 -1 (-4150 1150)(-4450 1150);
WIRE 16 -1 (-4450 1050)(-4450 1150);
WIRE 16 -1 (-3850 1150)(-4150 1150);
WIRE 16 -1 (-4150 1050)(-4150 1150);
WIRE 16 -1 (-3850 1050)(-3850 1150);
WIRE 16 -1 (-5050 1325)(-5050 1450);
WIRE 16 -1 (-5350 625)(-5350 650);
WIRE 16 -1 (-5350 650)(-5650 650);
WIRE 16 -1 (-5350 750)(-5350 650);
WIRE 16 -1 (-5950 650)(-5650 650);
WIRE 16 -1 (-5650 750)(-5650 650);
WIRE 16 -1 (-5950 750)(-5950 650);
WIRE 16 -1 (-5950 1650)(-5950 1800);
WIRE 16 -1 (-5950 1050)(-5950 1100);
WIRE 16 -1 (-5950 1050)(-5650 1050);
WIRE 16 -1 (-5950 950)(-5950 1050);
WIRE 16 -1 (-5350 1050)(-5650 1050);
WIRE 16 -1 (-5650 950)(-5650 1050);
WIRE 16 -1 (-5350 950)(-5350 1050);
WIRE 16 -1 (-7750 2025)(-7750 2050);
WIRE 16 -1 (-7450 2050)(-7750 2050);
WIRE 16 -1 (-7750 2150)(-7750 2050);
WIRE 16 -1 (-7150 2050)(-7450 2050);
WIRE 16 -1 (-7450 2150)(-7450 2050);
WIRE 16 -1 (-6850 2050)(-7150 2050);
WIRE 16 -1 (-7150 2150)(-7150 2050);
WIRE 16 -1 (-6550 2050)(-6850 2050);
WIRE 16 -1 (-6850 2150)(-6850 2050);
WIRE 16 -1 (-6550 2150)(-6550 2050);
WIRE 16 -1 (-7750 1325)(-7750 1350);
WIRE 16 -1 (-7750 1350)(-7450 1350);
WIRE 16 -1 (-7750 1450)(-7750 1350);
WIRE 16 -1 (-7150 1350)(-7450 1350);
WIRE 16 -1 (-7450 1450)(-7450 1350);
WIRE 16 -1 (-6850 1350)(-7150 1350);
WIRE 16 -1 (-7150 1450)(-7150 1350);
WIRE 16 -1 (-6550 1350)(-6850 1350);
WIRE 16 -1 (-6850 1450)(-6850 1350);
WIRE 16 -1 (-6550 1450)(-6550 1350);
WIRE 16 -1 (-750 1975)(-750 2000);
WIRE 16 -1 (-750 2000)(-1000 2000);
WIRE 16 -1 (-750 2125)(-750 2000);
WIRE 16 -1 (-1250 2000)(-1000 2000);
WIRE 16 -1 (-1000 2125)(-1000 2000);
WIRE 16 -1 (-1500 2000)(-1250 2000);
WIRE 16 -1 (-1250 2125)(-1250 2000);
WIRE 16 -1 (-1500 2000)(-1750 2000);
WIRE 16 -1 (-1500 2125)(-1500 2000);
WIRE 16 -1 (-2000 2000)(-1750 2000);
WIRE 16 -1 (-1750 2125)(-1750 2000);
WIRE 16 -1 (-2000 2000)(-2250 2000);
WIRE 16 -1 (-2000 2125)(-2000 2000);
WIRE 16 -1 (-2500 2000)(-2250 2000);
WIRE 16 -1 (-2250 2125)(-2250 2000);
WIRE 16 -1 (-2500 2000)(-2750 2000);
WIRE 16 -1 (-2500 2125)(-2500 2000);
WIRE 16 -1 (-3000 2000)(-2750 2000);
WIRE 16 -1 (-2750 2125)(-2750 2000);
WIRE 16 -1 (-3000 2000)(-3250 2000);
WIRE 16 -1 (-3000 2125)(-3000 2000);
WIRE 16 -1 (-3500 2000)(-3250 2000);
WIRE 16 -1 (-3250 2125)(-3250 2000);
WIRE 16 -1 (-3500 2000)(-3750 2000);
WIRE 16 -1 (-3500 2125)(-3500 2000);
WIRE 16 -1 (-4000 2000)(-3750 2000);
WIRE 16 -1 (-3750 2125)(-3750 2000);
WIRE 16 -1 (-4000 2000)(-4250 2000);
WIRE 16 -1 (-4000 2125)(-4000 2000);
WIRE 16 -1 (-4250 2000)(-4500 2000);
WIRE 16 -1 (-4250 2125)(-4250 2000);
WIRE 16 -1 (-4750 2000)(-4500 2000);
WIRE 16 -1 (-4500 2125)(-4500 2000);
WIRE 16 -1 (-4750 2125)(-4750 2000);
WIRE 16 -1 (-6550 625)(-6550 750);
WIRE 16 -1 (-7750 2450)(-7750 2500);
WIRE 16 -1 (-7450 2450)(-7750 2450);
WIRE 16 -1 (-7750 2450)(-7750 2350);
WIRE 16 -1 (-7150 2450)(-7450 2450);
WIRE 16 -1 (-7450 2350)(-7450 2450);
WIRE 16 -1 (-6850 2450)(-7150 2450);
WIRE 16 -1 (-7150 2350)(-7150 2450);
WIRE 16 -1 (-6550 2450)(-6850 2450);
WIRE 16 -1 (-6850 2350)(-6850 2450);
WIRE 16 -1 (-6550 2450)(-6550 2350);
WIRE 16 -1 (-7750 1750)(-7750 1800);
WIRE 16 -1 (-7450 1750)(-7750 1750);
WIRE 16 -1 (-7750 1750)(-7750 1650);
WIRE 16 -1 (-7150 1750)(-7450 1750);
WIRE 16 -1 (-7450 1650)(-7450 1750);
WIRE 16 -1 (-6850 1750)(-7150 1750);
WIRE 16 -1 (-7150 1650)(-7150 1750);
WIRE 16 -1 (-6850 1750)(-6550 1750);
WIRE 16 -1 (-6850 1650)(-6850 1750);
WIRE 16 -1 (-6550 1750)(-6550 1650);
WIRE 16 -1 (-3550 4275)(-3550 4300);
WIRE 16 -1 (-3550 4300)(-3300 4300);
WIRE 16 -1 (-3550 4400)(-3550 4300);
WIRE 16 -1 (-3300 4300)(-3050 4300);
WIRE 16 -1 (-3300 4400)(-3300 4300);
WIRE 16 -1 (-3050 4300)(-2800 4300);
WIRE 16 -1 (-3050 4400)(-3050 4300);
WIRE 16 -1 (-2800 4300)(-2550 4300);
WIRE 16 -1 (-2800 4400)(-2800 4300);
WIRE 16 -1 (-2550 4300)(-2300 4300);
WIRE 16 -1 (-2550 4400)(-2550 4300);
WIRE 16 -1 (-2300 4300)(-2050 4300);
WIRE 16 -1 (-2300 4400)(-2300 4300);
WIRE 16 -1 (-2050 4300)(-1800 4300);
WIRE 16 -1 (-2050 4400)(-2050 4300);
WIRE 16 -1 (-1800 4300)(-1550 4300);
WIRE 16 -1 (-1800 4400)(-1800 4300);
WIRE 16 -1 (-1550 4300)(-1300 4300);
WIRE 16 -1 (-1550 4400)(-1550 4300);
WIRE 16 -1 (-1300 4300)(-1050 4300);
WIRE 16 -1 (-1300 4400)(-1300 4300);
WIRE 16 -1 (-1050 4300)(-800 4300);
WIRE 16 -1 (-1050 4400)(-1050 4300);
WIRE 16 -1 (-550 4300)(-800 4300);
WIRE 16 -1 (-800 4400)(-800 4300);
WIRE 16 -1 (-550 4400)(-550 4300);
WIRE 16 -1 (-4100 3575)(-4100 3600);
WIRE 16 -1 (-3850 3600)(-4100 3600);
WIRE 16 -1 (-4100 3700)(-4100 3600);
WIRE 16 -1 (-3600 3600)(-3850 3600);
WIRE 16 -1 (-3850 3700)(-3850 3600);
WIRE 16 -1 (-3600 3600)(-3350 3600);
WIRE 16 -1 (-3600 3700)(-3600 3600);
WIRE 16 -1 (-3350 3600)(-3100 3600);
WIRE 16 -1 (-3350 3700)(-3350 3600);
WIRE 16 -1 (-2850 3600)(-3100 3600);
WIRE 16 -1 (-3100 3700)(-3100 3600);
WIRE 16 -1 (-2850 3700)(-2850 3600);
WIRE 16 -1 (-4100 4000)(-4100 4050);
WIRE 16 -1 (-3850 4000)(-4100 4000);
WIRE 16 -1 (-4100 3900)(-4100 4000);
WIRE 16 -1 (-3600 4000)(-3850 4000);
WIRE 16 -1 (-3850 3900)(-3850 4000);
WIRE 16 -1 (-3600 4000)(-3350 4000);
WIRE 16 -1 (-3600 3900)(-3600 4000);
WIRE 16 -1 (-3350 4000)(-3100 4000);
WIRE 16 -1 (-3350 3900)(-3350 4000);
WIRE 16 -1 (-2850 4000)(-3100 4000);
WIRE 16 -1 (-3100 3900)(-3100 4000);
WIRE 16 -1 (-2850 4000)(-2850 3900);
WIRE 16 -1 (-4100 2825)(-4100 2850);
WIRE 16 -1 (-3800 2850)(-4100 2850);
WIRE 16 -1 (-4100 3050)(-4100 2850);
WIRE 16 -1 (-3500 2850)(-3800 2850);
WIRE 16 -1 (-3800 3050)(-3800 2850);
WIRE 16 -1 (-3200 2850)(-3500 2850);
WIRE 16 -1 (-3500 3050)(-3500 2850);
WIRE 16 -1 (-3200 2850)(-3200 3050);
WIRE 16 -1 (-4100 3350)(-4100 3400);
WIRE 16 -1 (-3800 3350)(-4100 3350);
WIRE 16 -1 (-4100 3250)(-4100 3350);
WIRE 16 -1 (-3500 3350)(-3800 3350);
WIRE 16 -1 (-3800 3250)(-3800 3350);
WIRE 16 -1 (-3200 3350)(-3500 3350);
WIRE 16 -1 (-3500 3250)(-3500 3350);
WIRE 16 -1 (-3200 3350)(-3200 3250);
WIRE 16 -1 (-7750 4000)(-7750 4050);
WIRE 16 -1 (-7050 4000)(-7750 4000);
WIRE 16 -1 (-7750 4000)(-7750 3900);
WIRE 16 -1 (-6750 4000)(-7050 4000);
WIRE 16 -1 (-7050 3900)(-7050 4000);
WIRE 16 -1 (-6750 4000)(-6750 3900);
WIRE 3 682 (-4800 2600)(-100 2600);
WIRE 3 682 (-100 2600)(-100 1700);
WIRE 3 682 (-4800 1700)(-4800 2600);
WIRE 3 682 (-4800 1700)(-100 1700);
WIRE 3 682 (-1350 1600)(-1350 950);
WIRE 3 682 (-600 1600)(-1350 1600);
WIRE 3 682 (-1350 950)(-600 950);
WIRE 3 682 (-600 950)(-600 1600);
WIRE 3 682 (-2000 4150)(-2000 3500);
WIRE 3 682 (-3700 4150)(-2000 4150);
WIRE 3 682 (-2000 3500)(-1050 3500);
WIRE 3 682 (-1050 3500)(-1050 2750);
WIRE 3 682 (-3700 4850)(-3700 4150);
WIRE 3 682 (-100 4850)(-3700 4850);
WIRE 3 682 (-100 2750)(-1050 2750);
WIRE 3 682 (-100 2750)(-100 4850);
WIRE 16 2175 (-50 350)(-7950 350);
WIRE 16 2175 (-50 2650)(-50 350);
WIRE 16 2175 (-7950 350)(-7950 2650);
WIRE 16 2175 (-7950 2650)(-50 2650);
WIRE 16 2175 (-7950 2700)(-7950 4875);
WIRE 16 2175 (-50 2700)(-7950 2700);
WIRE 16 2175 (-7950 4875)(-50 4875);
WIRE 16 2175 (-50 4875)(-50 2700);
WIRE 3 682 (-1000 2800)(-250 2800);
WIRE 3 682 (-1000 3500)(-1000 2800);
WIRE 3 682 (-250 2800)(-250 3500);
WIRE 3 682 (-250 3500)(-1000 3500);
WIRE 3 682 (-5100 2400)(-5100 2150);
WIRE 3 682 (-4950 2400)(-5100 2400);
WIRE 3 682 (-5100 2150)(-4950 2150);
WIRE 3 682 (-4950 2150)(-4950 2400);
WIRE 3 682 (-5550 2400)(-5750 2400);
WIRE 3 682 (-5550 2100)(-5550 2400);
WIRE 3 682 (-5750 2400)(-5750 2100);
WIRE 3 682 (-5750 2100)(-5550 2100);
WIRE 3 682 (-7450 4350)(-7200 4350);
WIRE 3 682 (-7450 4650)(-7450 4350);
WIRE 3 682 (-7200 4350)(-7200 4650);
WIRE 3 682 (-7200 4650)(-7450 4650);
WIRE 3 682 (-7800 1000)(-7800 700);
WIRE 3 682 (-7700 1000)(-7800 1000);
WIRE 3 682 (-7800 700)(-7700 700);
WIRE 3 682 (-7700 700)(-7700 1000);
WIRE 3 682 (-7650 1000)(-7650 700);
WIRE 3 682 (-6650 1000)(-7650 1000);
WIRE 3 682 (-7650 700)(-6650 700);
WIRE 3 682 (-6650 700)(-6650 1000);
WIRE 3 682 (-7450 2950)(-7350 2950);
WIRE 3 682 (-7450 3250)(-7450 2950);
WIRE 3 682 (-7350 2950)(-7350 3250);
WIRE 3 682 (-7350 3250)(-7450 3250);
WIRE 3 682 (-7350 3950)(-7450 3950);
WIRE 3 682 (-7350 3650)(-7350 3950);
WIRE 3 682 (-7450 3950)(-7450 3650);
WIRE 3 682 (-7450 3650)(-7350 3650);
WIRE 3 682 (-7250 3950)(-7250 3650);
WIRE 3 682 (-7150 3950)(-7250 3950);
WIRE 3 682 (-7250 3650)(-7150 3650);
WIRE 3 682 (-7150 3650)(-7150 3950);
WIRE 3 682 (-6000 3650)(-5900 3650);
WIRE 3 682 (-6000 3950)(-6000 3650);
WIRE 3 682 (-5900 3650)(-5900 3950);
WIRE 3 682 (-5900 3950)(-6000 3950);
WIRE 3 682 (-5750 1700)(-5750 1450);
WIRE 3 682 (-5600 1700)(-5750 1700);
WIRE 3 682 (-5750 1450)(-5600 1450);
WIRE 3 682 (-5600 1450)(-5600 1700);
WIRE 3 682 (-5650 3000)(-5400 3000);
WIRE 3 682 (-5650 3300)(-5650 3000);
WIRE 3 682 (-5400 3000)(-5400 3300);
WIRE 3 682 (-5400 3300)(-5650 3300);
WIRE 3 682 (-6000 2400)(-6000 2100);
WIRE 3 682 (-5800 2400)(-6000 2400);
WIRE 3 682 (-6000 2100)(-5800 2100);
WIRE 3 682 (-5800 2100)(-5800 2400);
DOT 1 (-1300 3650);
DOT 1 (-1050 3650);
DOT 1 (-800 2950);
DOT 1 (-800 3300);
DOT 1 (-1800 3650);
DOT 1 (-1550 4000);
DOT 1 (-3550 4300);
DOT 1 (-3300 4300);
DOT 1 (-1300 4000);
DOT 1 (-3100 4000);
DOT 1 (-4250 2450);
DOT 1 (-1550 3650);
DOT 1 (-2550 4300);
DOT 1 (-1750 2450);
DOT 1 (-800 3650);
DOT 1 (-800 4000);
DOT 1 (-1800 4000);
DOT 1 (-1050 4000);
DOT 1 (-800 4650);
DOT 1 (-2800 4650);
DOT 1 (-3050 4650);
DOT 1 (-3300 4650);
DOT 1 (-3550 4650);
DOT 1 (-3050 4300);
DOT 1 (-2800 4300);
DOT 1 (-2550 4650);
DOT 1 (-2300 4300);
DOT 1 (-2300 4650);
DOT 1 (-2050 4300);
DOT 1 (-2050 4650);
DOT 1 (-1800 4300);
DOT 1 (-1800 4650);
DOT 1 (-1550 4300);
DOT 1 (-1550 4650);
DOT 1 (-1300 4300);
DOT 1 (-1300 4650);
DOT 1 (-1050 4300);
DOT 1 (-1050 4650);
DOT 1 (-800 4300);
DOT 1 (-2850 700);
DOT 1 (-4750 2450);
DOT 1 (-4000 2450);
DOT 1 (-4500 2450);
DOT 1 (-2250 2000);
DOT 1 (-3750 2450);
DOT 1 (-4500 2000);
DOT 1 (-4000 2000);
DOT 1 (-3500 2000);
DOT 1 (-5000 2950);
DOT 1 (-7750 2450);
DOT 1 (-6850 2450);
DOT 1 (-3500 3350);
DOT 1 (-3350 3600);
DOT 1 (-5950 4700);
DOT 1 (-5950 4300);
DOT 1 (-4150 700);
DOT 1 (-3850 700);
DOT 1 (-2550 700);
DOT 1 (-2250 700);
DOT 1 (-5950 1050);
DOT 1 (-7450 1350);
DOT 1 (-7450 2050);
DOT 1 (-6850 2050);
DOT 1 (-5650 650);
DOT 1 (-5350 650);
DOT 1 (-5650 1050);
DOT 1 (-7150 1350);
DOT 1 (-6850 1750);
DOT 1 (-7150 1750);
DOT 1 (-7750 2050);
DOT 1 (-7150 2050);
DOT 1 (-7450 2450);
DOT 1 (-7150 2450);
DOT 1 (-6850 1350);
DOT 1 (-7450 1750);
DOT 1 (-7750 1350);
DOT 1 (-7750 1750);
DOT 1 (-2850 1150);
DOT 1 (-3200 1150);
DOT 1 (-4100 2850);
DOT 1 (-3600 3600);
DOT 1 (-3600 4000);
DOT 1 (-4100 3600);
DOT 1 (-3350 4000);
DOT 1 (-3100 3600);
DOT 1 (-5200 4000);
DOT 1 (-4900 3600);
DOT 1 (-5200 3600);
DOT 1 (-4100 4000);
DOT 1 (-3850 4000);
DOT 1 (-5800 4000);
DOT 1 (-5650 4300);
DOT 1 (-5350 4700);
DOT 1 (-5350 4300);
DOT 1 (-5050 4700);
DOT 1 (-5050 4300);
DOT 1 (-4750 4700);
DOT 1 (-4750 4300);
DOT 1 (-5800 3600);
DOT 1 (-5500 4000);
DOT 1 (-5950 3350);
DOT 1 (-5950 2950);
DOT 1 (-5300 2950);
DOT 1 (-5500 3600);
DOT 1 (-5000 3350);
DOT 1 (-5300 3350);
DOT 1 (-4900 4000);
DOT 1 (-3850 3600);
DOT 1 (-7750 4700);
DOT 1 (-7750 4300);
DOT 1 (-5650 4700);
DOT 1 (-4100 3350);
DOT 1 (-7750 3600);
DOT 1 (-7750 3300);
DOT 1 (-7050 4000);
DOT 1 (-7050 4700);
DOT 1 (-7050 4300);
DOT 1 (-7750 4000);
DOT 1 (-7750 2900);
DOT 1 (-7050 3600);
DOT 1 (-7250 3300);
DOT 1 (-6950 3300);
DOT 1 (-7250 2900);
DOT 1 (-6950 2900);
DOT 1 (-4150 1150);
DOT 1 (-4450 1150);
DOT 1 (-1950 700);
DOT 1 (-2250 1150);
DOT 1 (-2550 1150);
DOT 1 (-3800 3350);
DOT 1 (-3800 2850);
DOT 1 (-3500 2850);
DOT 1 (-3750 2000);
DOT 1 (-3250 2000);
DOT 1 (-3000 2000);
DOT 1 (-2750 2000);
DOT 1 (-2500 2000);
DOT 1 (-2000 2000);
DOT 1 (-3500 2450);
DOT 1 (-3250 2450);
DOT 1 (-3000 2450);
DOT 1 (-2750 2450);
DOT 1 (-2500 2450);
DOT 1 (-2250 2450);
DOT 1 (-2000 2450);
DOT 1 (-1250 2000);
DOT 1 (-750 2000);
DOT 1 (-1500 2450);
DOT 1 (-1250 2450);
DOT 1 (-1000 2450);
DOT 1 (-1750 2000);
DOT 1 (-1500 2000);
DOT 1 (-1000 2000);
DOT 1 (-4250 2000);
FORCENOTE
TP FAB3 ADD CAP 0919
(-1000 2750) 0;
DISPLAY LEFT (-1000 2750);
DISPLAY 0.638298 (-1000 2750);
PAINT RED (-1000 2750);
FORCENOTE
REMOVE DURING MASS PRODUCTION
(-2775 2525) 0;
DISPLAY LEFT (-2775 2525);
DISPLAY 1.021277 (-2775 2525);
PAINT PURPLE (-2775 2525);
FORCENOTE
FULL CAP CONFIG FOR -P SUPPORT.
(-1340 415) 0;
DISPLAY LEFT (-1340 415);
PAINT PURPLE (-1340 415);
FORCENOTE
TP FAB1 ADD CAP 0314
(-1350 900) 0;
DISPLAY LEFT (-1350 900);
DISPLAY 0.638298 (-1350 900);
PAINT RED (-1350 900);
FORCENOTE
FULL CAP CONFIG FOR -P SUPPORT.
(-2690 3015) 0;
DISPLAY LEFT (-2690 3015);
PAINT PURPLE (-2690 3015);
FORCENOTE
PVMCP: 22UF, 603, 21X
(-3340 4715) 0;
DISPLAY LEFT (-3340 4715);
PAINT PURPLE (-3340 4715);
FORCENOTE
TP FAB4 ADD ATTRIBUTE GROUP=PWR_MCP_CAP 20170508
(-3700 4100) 0;
DISPLAY LEFT (-3700 4100);
DISPLAY 0.638298 (-3700 4100);
PAINT RED (-3700 4100);
FORCENOTE
PVCCIO: 22UF, 603, 6X
(-4065 4040) 0;
DISPLAY LEFT (-4065 4040);
PAINT PURPLE (-4065 4040);
FORCENOTE
(DEBUG ONLY)
(-3640 2479) 0;
DISPLAY LEFT (-3640 2479);
DISPLAY 1.021277 (-3640 2479);
PAINT PURPLE (-3640 2479);
FORCENOTE
PVMCP: 100UF, 805, 17X
(-3665 2540) 0;
DISPLAY LEFT (-3665 2540);
PAINT PURPLE (-3665 2540);
FORCENOTE
(DEBUG ONLY)
(-2390 4704) 0;
DISPLAY LEFT (-2390 4704);
DISPLAY 1.021277 (-2390 4704);
PAINT PURPLE (-2390 4704);
FORCENOTE
TP FAB1 MOVE TO PAGE 220 0311
(-5775 1750) 0;
DISPLAY LEFT (-5775 1750);
DISPLAY 0.638298 (-5775 1750);
PAINT RED (-5775 1750);
FORCENOTE
TP FAB3 CHANGE CAP FROM 47UF TO 100UF 1004
(-4800 1625) 0;
DISPLAY LEFT (-4800 1625);
DISPLAY 0.638298 (-4800 1625);
PAINT RED (-4800 1625);
FORCENOTE
TP FAB4 ADD ATTRIBUTE GROUP=PWR_MCP_CAP 20170508
(-4800 1575) 0;
DISPLAY LEFT (-4800 1575);
DISPLAY 0.638298 (-4800 1575);
PAINT RED (-4800 1575);
FORCENOTE
PVCCIO: 47UF/805/3X, 22UF/603/2X
(-2965 1365) 0;
DISPLAY LEFT (-2965 1365);
PAINT PURPLE (-2965 1365);
FORCENOTE
ROOM = PVCCIN_CPU0_DECAP_VR
(-7890 215) 0;
DISPLAY LEFT (-7890 215);
DISPLAY 2.446809 (-7890 215);
PAINT PURPLE (-7890 215);
FORCENOTE
TP FAB1 MOVE TO PAGE 220 0311
(-5975 2050) 0;
DISPLAY LEFT (-5975 2050);
DISPLAY 0.638298 (-5975 2050);
PAINT RED (-5975 2050);
FORCENOTE
TP FAB1 MOVE TO PAGE 217 0318
(-6075 2450) 0;
DISPLAY LEFT (-6075 2450);
DISPLAY 0.638298 (-6075 2450);
PAINT RED (-6075 2450);
FORCENOTE
PVCCIN: 47UF, 805, 17X
(-7290 2540) 0;
DISPLAY LEFT (-7290 2540);
PAINT PURPLE (-7290 2540);
FORCENOTE
TP FAB1 MOVE TO PAGE 217 0314
(-5750 3350) 0;
DISPLAY LEFT (-5750 3350);
DISPLAY 0.638298 (-5750 3350);
PAINT RED (-5750 3350);
FORCENOTE
TP FAB1 MOVE TO PAGE 220 0314
(-7475 3350) 0;
DISPLAY LEFT (-7475 3350);
DISPLAY 1.021277 (-7475 3350);
PAINT RED (-7475 3350);
FORCENOTE
TP FAB1 MOVE TO PAGE 217 0314
(-5925 4025) 0;
DISPLAY LEFT (-5925 4025);
DISPLAY 0.638298 (-5925 4025);
PAINT RED (-5925 4025);
FORCENOTE
TP FAB1 MOVE TO PAGE 220 0314
(-7550 4750) 0;
DISPLAY LEFT (-7550 4750);
DISPLAY 0.638298 (-7550 4750);
PAINT RED (-7550 4750);
FORCENOTE
PVCCIN: 22UF/603/25X
(-7465 4815) 0;
DISPLAY LEFT (-7465 4815);
PAINT PURPLE (-7465 4815);
FORCENOTE
TP FAB1 MOVE TO PAGE 220 0318
(-7800 1025) 0;
DISPLAY LEFT (-7800 1025);
DISPLAY 0.638298 (-7800 1025);
PAINT RED (-7800 1025);
FORCENOTE
TP FAB1 MOVE TO PAGE 217 0311
(-7650 650) 0;
DISPLAY LEFT (-7650 650);
DISPLAY 0.638298 (-7650 650);
PAINT RED (-7650 650);
FORCENOTE
TP FAB1 MOVE TO PAGE 220 0314
(-7550 4050) 0;
DISPLAY LEFT (-7550 4050);
DISPLAY 0.638298 (-7550 4050);
PAINT RED (-7550 4050);
FORCENOTE
TP FAB1 MOVE TO PAGE 217 0314
(-7350 4000) 0;
DISPLAY LEFT (-7350 4000);
DISPLAY 0.638298 (-7350 4000);
PAINT RED (-7350 4000);
QUIT
